FILE_TYPE = MACRO_DRAWING;
SET COLOR_WIRE YELLOW;
SET COLOR_PROP MONO;
SET COLOR_DOT WHITE;
SET COLOR_ARC YELLOW;
SET COLOR_BODY GREEN;
SET COLOR_NOTE MONO;
SET PROP_DISPLAY VALUE;
SET PAGE_NUMBER P22;
FORCEADD OFFPAGE..4
(-1700 2850);
FORCEPROP 2 LAST $XR3 56 
J 0
(-1154 2850);
DISPLAY 0.638298 (-1154 2850);
PAINT MONO (-1154 2850);
FORCEPROP 2 LAST $XR2 254 
J 0
(-1274 2850);
DISPLAY 0.638298 (-1274 2850);
PAINT MONO (-1274 2850);
FORCEPROP 2 LAST $XR1 118 
J 0
(-1394 2850);
DISPLAY 0.638298 (-1394 2850);
PAINT MONO (-1394 2850);
FORCEPROP 2 LAST $XR0 111 
J 0
(-1514 2850);
DISPLAY 0.638298 (-1514 2850);
PAINT MONO (-1514 2850);
FORCEPROP 2 LAST CDS_LIB mstr_standard
J 0
(-1700 2850);
DISPLAY 0.787234 (-1700 2850);
PAINT MONO (-1700 2850);
DISPLAY INVISIBLE (-1700 2850);
FORCEPROP 2 LAST PATH I185
J 0
(-1375 2900);
DISPLAY 1.021277 (-1375 2900);
PAINT ORANGE (-1375 2900);
DISPLAY INVISIBLE (-1375 2900);
FORCEPROP 1 LAST OFFPAGE TRUE
J 0
(-1375 2725);
DISPLAY 0.680851 (-1375 2725);
PAINT GREEN (-1375 2725);
DISPLAY INVISIBLE (-1375 2725);
FORCEPROP 1 LAST COMMENT_BODY TRUE
J 0
(-1725 2750);
DISPLAY 0.680851 (-1725 2750);
PAINT PEACH (-1725 2750);
DISPLAY INVISIBLE (-1725 2750);
FORCEADD OFFPAGE..4
(-1700 1850);
FORCEPROP 2 LAST $XR0 104 
J 0
(-1514 1850);
DISPLAY 0.638298 (-1514 1850);
PAINT MONO (-1514 1850);
FORCEPROP 2 LAST PATH I186
J 0
(-1500 1900);
DISPLAY 1.021277 (-1500 1900);
PAINT ORANGE (-1500 1900);
DISPLAY INVISIBLE (-1500 1900);
FORCEPROP 2 LAST CDS_LIB mstr_standard
J 0
(-1700 1850);
PAINT ORANGE (-1700 1850);
DISPLAY INVISIBLE (-1700 1850);
FORCEPROP 1 LAST OFFPAGE TRUE
J 0
(-1375 1725);
DISPLAY 0.872340 (-1375 1725);
PAINT GREEN (-1375 1725);
DISPLAY INVISIBLE (-1375 1725);
FORCEPROP 1 LAST COMMENT_BODY TRUE
J 0
(-1725 1750);
DISPLAY 0.872340 (-1725 1750);
PAINT GREEN (-1725 1750);
DISPLAY INVISIBLE (-1725 1750);
FORCEADD RES..2
(-300 2775);
FORCEPROP 1 LASTPIN (-300 2875) $PN 1
J 0
(-295 2837);
DISPLAY 0.617021 (-295 2837);
PAINT ORANGE (-295 2837);
FORCEPROP 1 LASTPIN (-300 2675) $PN 2
J 0
(-295 2685);
DISPLAY 0.617021 (-295 2685);
PAINT ORANGE (-295 2685);
FORCEPROP 1 LAST WATTAGE 1/16W
J 0
(-260 2750);
DISPLAY 0.617021 (-260 2750);
PAINT SKYBLUE (-260 2750);
FORCEPROP 1 LAST MATERIAL CHIP
J 0
(-260 2700);
DISPLAY 0.617021 (-260 2700);
PAINT SKYBLUE (-260 2700);
FORCEPROP 1 LAST PACK_TYPE 0402
J 0
(-260 2600);
DISPLAY 0.617021 (-260 2600);
PAINT SKYBLUE (-260 2600);
FORCEPROP 1 LAST TOLERANCE 1%
J 0
(-255 2800);
DISPLAY 0.617021 (-255 2800);
PAINT SKYBLUE (-255 2800);
FORCEPROP 1 LAST VALUE 49.9
J 0
(-255 2850);
DISPLAY 0.617021 (-255 2850);
PAINT SKYBLUE (-255 2850);
FORCEPROP 1 LAST PART_NUMBER G21796-047
J 0
(-260 2650);
DISPLAY 0.617021 (-260 2650);
PAINT BLUE (-260 2650);
FORCEPROP 1 LAST LOCATION R5R1
J 0
(-255 2900);
DISPLAY 0.617021 (-255 2900);
PAINT AQUA (-255 2900);
FORCEPROP 0 LAST ROOM CPU0
J 0
(-250 3000);
DISPLAY 1.021277 (-250 3000);
PAINT ORANGE (-250 3000);
DISPLAY INVISIBLE (-250 3000);
FORCEPROP 1 LAST PATH I188
J 0
(-250 2950);
DISPLAY 0.978723 (-250 2950);
PAINT WHITE (-250 2950);
DISPLAY INVISIBLE (-250 2950);
FORCEPROP 2 LAST CDS_LOCATION R5R1
J 0
(-255 2900);
DISPLAY 0.617021 (-255 2900);
PAINT AQUA (-255 2900);
DISPLAY INVISIBLE (-255 2900);
FORCEPROP 2 LAST SEC 1
J 0
(-250 3000);
DISPLAY 0.680851 (-250 3000);
PAINT MONO (-250 3000);
DISPLAY INVISIBLE (-250 3000);
FORCEPROP 2 LAST CDS_LIB mstr_discrete
J 0
(-300 2775);
PAINT MONO (-300 2775);
DISPLAY INVISIBLE (-300 2775);
FORCEPROP 2 LAST SEC_TYPE 0402
J 0
(-250 3000);
DISPLAY 1.021277 (-250 3000);
PAINT ORANGE (-250 3000);
DISPLAY INVISIBLE (-250 3000);
FORCEADD GND..1
(-300 2450);
FORCEPROP 3 LASTPIN (-300 2500) SIG_NAME GND\g
J 0
(-290 2510);
DISPLAY 0.659574 (-290 2510);
PAINT MONO (-290 2510);
DISPLAY INVISIBLE (-290 2510);
FORCEPROP 1 LAST PATH I189
J 0
(-225 2450);
DISPLAY 0.872340 (-225 2450);
PAINT AQUA (-225 2450);
DISPLAY INVISIBLE (-225 2450);
FORCEPROP 1 LAST SIZE 1B
J 0
(-225 2400);
DISPLAY 1.170213 (-225 2400);
PAINT GREEN (-225 2400);
DISPLAY INVISIBLE (-225 2400);
FORCEPROP 2 LAST CDS_LIB mstr_symbols
J 0
(-300 2450);
PAINT MONO (-300 2450);
DISPLAY INVISIBLE (-300 2450);
FORCEPROP 1 LAST VOLTAGE 0.0V
J 0
(-345 2407);
DISPLAY 0.340426 (-345 2407);
PAINT SKYBLUE (-345 2407);
DISPLAY INVISIBLE (-345 2407);
FORCEPROP 1 LAST BODY_TYPE PLUMBING
J 0
(-345 2407);
DISPLAY 0.340426 (-345 2407);
PAINT GREEN (-345 2407);
DISPLAY INVISIBLE (-345 2407);
FORCEPROP 1 LAST HDL_POWER GND
J 0
(-300 2600);
DISPLAY 0.702128 (-300 2600);
PAINT GREEN (-300 2600);
DISPLAY INVISIBLE (-300 2600);
FORCEADD RES..2
(-575 2775);
FORCEPROP 1 LASTPIN (-575 2875) $PN 1
J 0
(-570 2837);
DISPLAY 0.617021 (-570 2837);
PAINT ORANGE (-570 2837);
FORCEPROP 1 LASTPIN (-575 2675) $PN 2
J 0
(-570 2685);
DISPLAY 0.617021 (-570 2685);
PAINT ORANGE (-570 2685);
FORCEPROP 1 LAST WATTAGE 1/16W
J 0
(-535 2750);
DISPLAY 0.617021 (-535 2750);
PAINT SKYBLUE (-535 2750);
FORCEPROP 1 LAST MATERIAL CHIP
J 0
(-535 2700);
DISPLAY 0.617021 (-535 2700);
PAINT SKYBLUE (-535 2700);
FORCEPROP 1 LAST PACK_TYPE 0402
J 0
(-535 2600);
DISPLAY 0.617021 (-535 2600);
PAINT SKYBLUE (-535 2600);
FORCEPROP 1 LAST TOLERANCE 1%
J 0
(-530 2800);
DISPLAY 0.617021 (-530 2800);
PAINT SKYBLUE (-530 2800);
FORCEPROP 1 LAST VALUE 49.9
J 0
(-530 2850);
DISPLAY 0.617021 (-530 2850);
PAINT SKYBLUE (-530 2850);
FORCEPROP 1 LAST PART_NUMBER G21796-047
J 0
(-535 2650);
DISPLAY 0.617021 (-535 2650);
PAINT BLUE (-535 2650);
FORCEPROP 1 LAST LOCATION R5P4
J 0
(-530 2900);
DISPLAY 0.617021 (-530 2900);
PAINT AQUA (-530 2900);
FORCEPROP 0 LAST ROOM CPU0
J 0
(-525 3000);
DISPLAY 1.021277 (-525 3000);
PAINT ORANGE (-525 3000);
DISPLAY INVISIBLE (-525 3000);
FORCEPROP 1 LAST PATH I190
J 0
(-525 2950);
DISPLAY 0.978723 (-525 2950);
PAINT WHITE (-525 2950);
DISPLAY INVISIBLE (-525 2950);
FORCEPROP 2 LAST CDS_LOCATION R5P4
J 0
(-530 2900);
DISPLAY 0.617021 (-530 2900);
PAINT AQUA (-530 2900);
DISPLAY INVISIBLE (-530 2900);
FORCEPROP 2 LAST SEC 1
J 0
(-525 3000);
DISPLAY 0.680851 (-525 3000);
PAINT MONO (-525 3000);
DISPLAY INVISIBLE (-525 3000);
FORCEPROP 2 LAST CDS_LIB mstr_discrete
J 0
(-575 2775);
PAINT MONO (-575 2775);
DISPLAY INVISIBLE (-575 2775);
FORCEPROP 2 LAST SEC_TYPE 0402
J 0
(-525 3000);
DISPLAY 1.021277 (-525 3000);
PAINT ORANGE (-525 3000);
DISPLAY INVISIBLE (-525 3000);
FORCEADD OFFPAGE..4
(-1700 2050);
FORCEPROP 2 LAST $XR0 90 
J 0
(-1514 2050);
DISPLAY 0.638298 (-1514 2050);
PAINT MONO (-1514 2050);
FORCEPROP 2 LAST PATH I195
J 0
(-1500 2100);
DISPLAY 1.021277 (-1500 2100);
PAINT ORANGE (-1500 2100);
DISPLAY INVISIBLE (-1500 2100);
FORCEPROP 2 LAST CDS_LIB mstr_standard
J 0
(-1700 2050);
DISPLAY 0.489362 (-1700 2050);
PAINT ORANGE (-1700 2050);
DISPLAY INVISIBLE (-1700 2050);
FORCEPROP 1 LAST OFFPAGE TRUE
J 0
(-1375 1925);
DISPLAY 0.680851 (-1375 1925);
PAINT GREEN (-1375 1925);
DISPLAY INVISIBLE (-1375 1925);
FORCEPROP 1 LAST COMMENT_BODY TRUE
J 0
(-1725 1950);
DISPLAY 0.680851 (-1725 1950);
PAINT PEACH (-1725 1950);
DISPLAY INVISIBLE (-1725 1950);
FORCEADD OFFPAGE..2
(-1700 2650);
FORCEPROP 2 LAST $XR0 92 
J 0
(-1511 2650);
DISPLAY 0.638298 (-1511 2650);
PAINT MONO (-1511 2650);
FORCEPROP 2 LAST CDS_LIB mstr_standard
J 0
(-1700 2650);
PAINT MONO (-1700 2650);
DISPLAY INVISIBLE (-1700 2650);
FORCEPROP 2 LAST PATH I196
J 0
(-1525 2725);
DISPLAY 1.021277 (-1525 2725);
PAINT ORANGE (-1525 2725);
DISPLAY INVISIBLE (-1525 2725);
FORCEPROP 1 LAST OFFPAGE TRUE
J 0
(-1375 2525);
DISPLAY 0.489362 (-1375 2525);
PAINT GREEN (-1375 2525);
DISPLAY INVISIBLE (-1375 2525);
FORCEPROP 1 LAST COMMENT_BODY TRUE
J 0
(-1745 2555);
DISPLAY 0.936170 (-1745 2555);
PAINT PEACH (-1745 2555);
DISPLAY INVISIBLE (-1745 2555);
FORCEADD OFFPAGE..4
(-1700 2450);
FORCEPROP 2 LAST $XR2 56 
J 0
(-1274 2450);
DISPLAY 0.638298 (-1274 2450);
PAINT MONO (-1274 2450);
FORCEPROP 2 LAST $XR1 255 
J 0
(-1394 2450);
DISPLAY 0.638298 (-1394 2450);
PAINT MONO (-1394 2450);
FORCEPROP 2 LAST $XR0 111 
J 0
(-1514 2450);
DISPLAY 0.638298 (-1514 2450);
PAINT MONO (-1514 2450);
FORCEPROP 2 LAST CDS_LIB mstr_standard
J 0
(-1700 2450);
DISPLAY 0.787234 (-1700 2450);
PAINT MONO (-1700 2450);
DISPLAY INVISIBLE (-1700 2450);
FORCEPROP 2 LAST PATH I197
J 0
(-1375 2500);
DISPLAY 1.021277 (-1375 2500);
PAINT ORANGE (-1375 2500);
DISPLAY INVISIBLE (-1375 2500);
FORCEPROP 1 LAST OFFPAGE TRUE
J 0
(-1375 2325);
DISPLAY 0.680851 (-1375 2325);
PAINT GREEN (-1375 2325);
DISPLAY INVISIBLE (-1375 2325);
FORCEPROP 1 LAST COMMENT_BODY TRUE
J 0
(-1725 2350);
DISPLAY 0.680851 (-1725 2350);
PAINT PEACH (-1725 2350);
DISPLAY INVISIBLE (-1725 2350);
FORCEADD OFFPAGE..4
(-1700 2700);
FORCEPROP 2 LAST $XR0 104 
J 0
(-1514 2700);
DISPLAY 0.638298 (-1514 2700);
PAINT MONO (-1514 2700);
FORCEPROP 2 LAST CDS_LIB mstr_standard
J 0
(-1700 2700);
PAINT MONO (-1700 2700);
DISPLAY INVISIBLE (-1700 2700);
FORCEPROP 2 LAST PATH I198
J 0
(-1525 2775);
DISPLAY 1.021277 (-1525 2775);
PAINT ORANGE (-1525 2775);
DISPLAY INVISIBLE (-1525 2775);
FORCEPROP 1 LAST OFFPAGE TRUE
J 0
(-1375 2575);
DISPLAY 0.680851 (-1375 2575);
PAINT GREEN (-1375 2575);
DISPLAY INVISIBLE (-1375 2575);
FORCEPROP 1 LAST COMMENT_BODY TRUE
J 0
(-1725 2600);
DISPLAY 0.680851 (-1725 2600);
PAINT PEACH (-1725 2600);
DISPLAY INVISIBLE (-1725 2600);
FORCEADD OFFPAGE..4
(-1700 1450);
FORCEPROP 2 LAST $XR0 103 
J 0
(-1514 1450);
DISPLAY 0.638298 (-1514 1450);
PAINT MONO (-1514 1450);
FORCEPROP 2 LAST PATH I199
J 0
(-1525 1525);
DISPLAY 1.021277 (-1525 1525);
PAINT ORANGE (-1525 1525);
DISPLAY INVISIBLE (-1525 1525);
FORCEPROP 2 LAST CDS_LIB mstr_standard
J 0
(-1700 1450);
PAINT MONO (-1700 1450);
DISPLAY INVISIBLE (-1700 1450);
FORCEPROP 1 LAST OFFPAGE TRUE
J 0
(-1375 1325);
DISPLAY 0.872340 (-1375 1325);
PAINT GREEN (-1375 1325);
DISPLAY INVISIBLE (-1375 1325);
FORCEPROP 1 LAST COMMENT_BODY TRUE
J 0
(-1725 1350);
DISPLAY 0.872340 (-1725 1350);
PAINT GREEN (-1725 1350);
DISPLAY INVISIBLE (-1725 1350);
FORCEADD OFFPAGE..4
(-1700 850);
FORCEPROP 2 LAST $XR0 103 
J 0
(-1514 850);
DISPLAY 0.638298 (-1514 850);
PAINT MONO (-1514 850);
FORCEPROP 2 LAST PATH I200
J 0
(-1525 925);
DISPLAY 1.021277 (-1525 925);
PAINT ORANGE (-1525 925);
DISPLAY INVISIBLE (-1525 925);
FORCEPROP 2 LAST CDS_LIB mstr_standard
J 0
(-1700 850);
PAINT MONO (-1700 850);
DISPLAY INVISIBLE (-1700 850);
FORCEPROP 1 LAST OFFPAGE TRUE
J 0
(-1375 725);
DISPLAY 0.872340 (-1375 725);
PAINT GREEN (-1375 725);
DISPLAY INVISIBLE (-1375 725);
FORCEPROP 1 LAST COMMENT_BODY TRUE
J 0
(-1725 750);
DISPLAY 0.872340 (-1725 750);
PAINT GREEN (-1725 750);
DISPLAY INVISIBLE (-1725 750);
FORCEADD VCC_CORE..1
(-1100 2325);
FORCEPROP 3 LASTPIN (-1100 2275) SIG_NAME PVCCMCP_CPU0\g
J 0
(-1090 2285);
DISPLAY 0.659574 (-1090 2285);
PAINT MONO (-1090 2285);
DISPLAY INVISIBLE (-1090 2285);
FORCEPROP 1 LAST HDL_POWER PVCCMCP_CPU0
J 1
(-1100 2375);
DISPLAY 0.617021 (-1100 2375);
PAINT GREEN (-1100 2375);
FORCEPROP 1 LAST PATH I202
J 0
(-1050 2350);
DISPLAY 0.872340 (-1050 2350);
PAINT AQUA (-1050 2350);
DISPLAY INVISIBLE (-1050 2350);
FORCEPROP 2 LAST CDS_LIB mstr_symbols
J 0
(-1100 2325);
PAINT ORANGE (-1100 2325);
DISPLAY INVISIBLE (-1100 2325);
FORCEADD VCC_CORE..1
(-7300 4475);
FORCEPROP 3 LASTPIN (-7300 4425) SIG_NAME P1V8_MCP_CPU0\g
J 0
(-7290 4435);
DISPLAY 0.659574 (-7290 4435);
PAINT MONO (-7290 4435);
DISPLAY INVISIBLE (-7290 4435);
FORCEPROP 1 LAST HDL_POWER P1V8_MCP_CPU0
J 1
(-7300 4525);
DISPLAY 0.617021 (-7300 4525);
PAINT GREEN (-7300 4525);
FORCEPROP 1 LAST PATH I203
J 0
(-7250 4500);
DISPLAY 0.872340 (-7250 4500);
PAINT AQUA (-7250 4500);
DISPLAY INVISIBLE (-7250 4500);
FORCEPROP 2 LAST CDS_LIB mstr_symbols
J 0
(-7300 4475);
PAINT ORANGE (-7300 4475);
DISPLAY INVISIBLE (-7300 4475);
FORCEADD SKX_EXT_B..2
(-4150 2550);
FORCEPROP 2 LASTPIN (-2900 4100) $PN AG54
J 0
(-2890 4110);
DISPLAY 0.617021 (-2890 4110);
PAINT ORANGE (-2890 4110);
FORCEPROP 2 LASTPIN (-5400 1450) $PN AD49
J 2
(-5410 1460);
DISPLAY 0.617021 (-5410 1460);
PAINT ORANGE (-5410 1460);
FORCEPROP 2 LASTPIN (-5400 1850) $PN V67
J 2
(-5410 1860);
DISPLAY 0.617021 (-5410 1860);
PAINT ORANGE (-5410 1860);
FORCEPROP 2 LASTPIN (-5400 1800) $PN W66
J 2
(-5410 1810);
DISPLAY 0.617021 (-5410 1810);
PAINT ORANGE (-5410 1810);
FORCEPROP 2 LASTPIN (-2900 2650) $PN AU14
J 0
(-2890 2660);
DISPLAY 0.617021 (-2890 2660);
PAINT ORANGE (-2890 2660);
FORCEPROP 2 LASTPIN (-2900 2700) $PN AK27
J 0
(-2890 2710);
DISPLAY 0.617021 (-2890 2710);
PAINT ORANGE (-2890 2710);
FORCEPROP 2 LASTPIN (-5400 3550) $PN C24
J 2
(-5410 3560);
DISPLAY 0.617021 (-5410 3560);
PAINT ORANGE (-5410 3560);
FORCEPROP 2 LASTPIN (-5400 3100) $PN E24
J 2
(-5410 3110);
DISPLAY 0.617021 (-5410 3110);
PAINT ORANGE (-5410 3110);
FORCEPROP 2 LASTPIN (-2900 3550) $PN AJ20
J 0
(-2890 3560);
DISPLAY 0.617021 (-2890 3560);
PAINT ORANGE (-2890 3560);
FORCEPROP 2 LASTPIN (-2900 2450) $PN AV21
J 0
(-2890 2460);
DISPLAY 0.617021 (-2890 2460);
PAINT ORANGE (-2890 2460);
FORCEPROP 2 LASTPIN (-2900 2050) $PN AW12
J 0
(-2890 2060);
DISPLAY 0.617021 (-2890 2060);
PAINT ORANGE (-2890 2060);
FORCEPROP 2 LASTPIN (-2900 2850) $PN AP17
J 0
(-2890 2860);
DISPLAY 0.617021 (-2890 2860);
PAINT ORANGE (-2890 2860);
FORCEPROP 2 LASTPIN (-2900 800) $PN AP61
J 0
(-2890 810);
DISPLAY 0.617021 (-2890 810);
PAINT ORANGE (-2890 810);
FORCEPROP 2 LASTPIN (-2900 850) $PN AP27
J 0
(-2890 860);
DISPLAY 0.617021 (-2890 860);
PAINT ORANGE (-2890 860);
FORCEPROP 2 LASTPIN (-2900 900) $PN AP25
J 0
(-2890 910);
DISPLAY 0.617021 (-2890 910);
PAINT ORANGE (-2890 910);
FORCEPROP 2 LASTPIN (-2900 950) $PN AP23
J 0
(-2890 960);
DISPLAY 0.617021 (-2890 960);
PAINT ORANGE (-2890 960);
FORCEPROP 2 LASTPIN (-2900 1000) $PN AN62
J 0
(-2890 1010);
DISPLAY 0.617021 (-2890 1010);
PAINT ORANGE (-2890 1010);
FORCEPROP 2 LASTPIN (-2900 1050) $PN AN60
J 0
(-2890 1060);
DISPLAY 0.617021 (-2890 1060);
PAINT ORANGE (-2890 1060);
FORCEPROP 2 LASTPIN (-2900 1100) $PN AN26
J 0
(-2890 1110);
DISPLAY 0.617021 (-2890 1110);
PAINT ORANGE (-2890 1110);
FORCEPROP 2 LASTPIN (-2900 1150) $PN AN24
J 0
(-2890 1160);
DISPLAY 0.617021 (-2890 1160);
PAINT ORANGE (-2890 1160);
FORCEPROP 2 LASTPIN (-2900 1200) $PN AN22
J 0
(-2890 1210);
DISPLAY 0.617021 (-2890 1210);
PAINT ORANGE (-2890 1210);
FORCEPROP 2 LASTPIN (-2900 1300) $PN AN18
J 0
(-2890 1310);
DISPLAY 0.617021 (-2890 1310);
PAINT ORANGE (-2890 1310);
FORCEPROP 2 LASTPIN (-2900 1350) $PN AM61
J 0
(-2890 1360);
DISPLAY 0.617021 (-2890 1360);
PAINT ORANGE (-2890 1360);
FORCEPROP 2 LASTPIN (-2900 1400) $PN AM59
J 0
(-2890 1410);
DISPLAY 0.617021 (-2890 1410);
PAINT ORANGE (-2890 1410);
FORCEPROP 2 LASTPIN (-2900 1450) $PN AM27
J 0
(-2890 1460);
DISPLAY 0.617021 (-2890 1460);
PAINT ORANGE (-2890 1460);
FORCEPROP 2 LASTPIN (-2900 1500) $PN AM25
J 0
(-2890 1510);
DISPLAY 0.617021 (-2890 1510);
PAINT ORANGE (-2890 1510);
FORCEPROP 2 LASTPIN (-2900 1550) $PN AM23
J 0
(-2890 1560);
DISPLAY 0.617021 (-2890 1560);
PAINT ORANGE (-2890 1560);
FORCEPROP 2 LASTPIN (-2900 1650) $PN AM21
J 0
(-2890 1660);
DISPLAY 0.617021 (-2890 1660);
PAINT ORANGE (-2890 1660);
FORCEPROP 2 LASTPIN (-2900 1700) $PN AL62
J 0
(-2890 1710);
DISPLAY 0.617021 (-2890 1710);
PAINT ORANGE (-2890 1710);
FORCEPROP 2 LASTPIN (-2900 1750) $PN AL60
J 0
(-2890 1760);
DISPLAY 0.617021 (-2890 1760);
PAINT ORANGE (-2890 1760);
FORCEPROP 2 LASTPIN (-2900 1800) $PN AL58
J 0
(-2890 1810);
DISPLAY 0.617021 (-2890 1810);
PAINT ORANGE (-2890 1810);
FORCEPROP 2 LASTPIN (-2900 1850) $PN AL26
J 0
(-2890 1860);
DISPLAY 0.617021 (-2890 1860);
PAINT ORANGE (-2890 1860);
FORCEPROP 2 LASTPIN (-2900 2000) $PN AL22
J 0
(-2890 2010);
DISPLAY 0.617021 (-2890 2010);
PAINT ORANGE (-2890 2010);
FORCEPROP 2 LASTPIN (-2900 2200) $PN AL20
J 0
(-2890 2210);
DISPLAY 0.617021 (-2890 2210);
PAINT ORANGE (-2890 2210);
FORCEPROP 2 LASTPIN (-2900 2250) $PN AK69
J 0
(-2890 2260);
DISPLAY 0.617021 (-2890 2260);
PAINT ORANGE (-2890 2260);
FORCEPROP 2 LASTPIN (-2900 2500) $PN AK61
J 0
(-2890 2510);
DISPLAY 0.617021 (-2890 2510);
PAINT ORANGE (-2890 2510);
FORCEPROP 2 LASTPIN (-2900 3250) $PN AK21
J 0
(-2890 3260);
DISPLAY 0.617021 (-2890 3260);
PAINT ORANGE (-2890 3260);
FORCEPROP 2 LASTPIN (-2900 3300) $PN AJ70
J 0
(-2890 3310);
DISPLAY 0.617021 (-2890 3310);
PAINT ORANGE (-2890 3310);
FORCEPROP 2 LASTPIN (-2900 3350) $PN AJ62
J 0
(-2890 3360);
DISPLAY 0.617021 (-2890 3360);
PAINT ORANGE (-2890 3360);
FORCEPROP 2 LASTPIN (-2900 3400) $PN AJ60
J 0
(-2890 3410);
DISPLAY 0.617021 (-2890 3410);
PAINT ORANGE (-2890 3410);
FORCEPROP 2 LASTPIN (-2900 3450) $PN AJ58
J 0
(-2890 3460);
DISPLAY 0.617021 (-2890 3460);
PAINT ORANGE (-2890 3460);
FORCEPROP 2 LASTPIN (-2900 3500) $PN AJ56
J 0
(-2890 3510);
DISPLAY 0.617021 (-2890 3510);
PAINT ORANGE (-2890 3510);
FORCEPROP 2 LASTPIN (-2900 3650) $PN AH73
J 0
(-2890 3660);
DISPLAY 0.617021 (-2890 3660);
PAINT ORANGE (-2890 3660);
FORCEPROP 2 LASTPIN (-2900 3700) $PN AH71
J 0
(-2890 3710);
DISPLAY 0.617021 (-2890 3710);
PAINT ORANGE (-2890 3710);
FORCEPROP 2 LASTPIN (-2900 3750) $PN AH57
J 0
(-2890 3760);
DISPLAY 0.617021 (-2890 3760);
PAINT ORANGE (-2890 3760);
FORCEPROP 2 LASTPIN (-2900 3800) $PN AH55
J 0
(-2890 3810);
DISPLAY 0.617021 (-2890 3810);
PAINT ORANGE (-2890 3810);
FORCEPROP 2 LASTPIN (-2900 3850) $PN AH19
J 0
(-2890 3860);
DISPLAY 0.617021 (-2890 3860);
PAINT ORANGE (-2890 3860);
FORCEPROP 2 LASTPIN (-2900 3900) $PN AH15
J 0
(-2890 3910);
DISPLAY 0.617021 (-2890 3910);
PAINT ORANGE (-2890 3910);
FORCEPROP 2 LASTPIN (-2900 3950) $PN AG72
J 0
(-2890 3960);
DISPLAY 0.617021 (-2890 3960);
PAINT ORANGE (-2890 3960);
FORCEPROP 2 LASTPIN (-2900 4050) $PN AG56
J 0
(-2890 4060);
DISPLAY 0.617021 (-2890 4060);
PAINT ORANGE (-2890 4060);
FORCEPROP 2 LASTPIN (-2900 4150) $PN AG52
J 0
(-2890 4160);
DISPLAY 0.617021 (-2890 4160);
PAINT ORANGE (-2890 4160);
FORCEPROP 2 LASTPIN (-2900 4200) $PN AG50
J 0
(-2890 4210);
DISPLAY 0.617021 (-2890 4210);
PAINT ORANGE (-2890 4210);
FORCEPROP 2 LASTPIN (-2900 4250) $PN AG48
J 0
(-2890 4260);
DISPLAY 0.617021 (-2890 4260);
PAINT ORANGE (-2890 4260);
FORCEPROP 2 LASTPIN (-2900 4300) $PN AG20
J 0
(-2890 4310);
DISPLAY 0.617021 (-2890 4310);
PAINT ORANGE (-2890 4310);
FORCEPROP 2 LASTPIN (-2900 4350) $PN AF71
J 0
(-2890 4360);
DISPLAY 0.617021 (-2890 4360);
PAINT ORANGE (-2890 4360);
FORCEPROP 2 LASTPIN (-5400 750) $PN AF53
J 2
(-5410 760);
DISPLAY 0.617021 (-5410 760);
PAINT ORANGE (-5410 760);
FORCEPROP 2 LASTPIN (-5400 900) $PN AF51
J 2
(-5410 910);
DISPLAY 0.617021 (-5410 910);
PAINT ORANGE (-5410 910);
FORCEPROP 2 LASTPIN (-5400 950) $PN AF49
J 2
(-5410 960);
DISPLAY 0.617021 (-5410 960);
PAINT ORANGE (-5410 960);
FORCEPROP 2 LASTPIN (-5400 1000) $PN AF47
J 2
(-5410 1010);
DISPLAY 0.617021 (-5410 1010);
PAINT ORANGE (-5410 1010);
FORCEPROP 2 LASTPIN (-5400 1050) $PN AF19
J 2
(-5410 1060);
DISPLAY 0.617021 (-5410 1060);
PAINT ORANGE (-5410 1060);
FORCEPROP 2 LASTPIN (-5400 1100) $PN AE72
J 2
(-5410 1110);
DISPLAY 0.617021 (-5410 1110);
PAINT ORANGE (-5410 1110);
FORCEPROP 2 LASTPIN (-5400 1150) $PN AE52
J 2
(-5410 1160);
DISPLAY 0.617021 (-5410 1160);
PAINT ORANGE (-5410 1160);
FORCEPROP 2 LASTPIN (-5400 1250) $PN AE50
J 2
(-5410 1260);
DISPLAY 0.617021 (-5410 1260);
PAINT ORANGE (-5410 1260);
FORCEPROP 2 LASTPIN (-5400 1300) $PN AE48
J 2
(-5410 1310);
DISPLAY 0.617021 (-5410 1310);
PAINT ORANGE (-5410 1310);
FORCEPROP 2 LASTPIN (-5400 1350) $PN AE46
J 2
(-5410 1360);
DISPLAY 0.617021 (-5410 1360);
PAINT ORANGE (-5410 1360);
FORCEPROP 2 LASTPIN (-5400 1400) $PN AD51
J 2
(-5410 1410);
DISPLAY 0.617021 (-5410 1410);
PAINT ORANGE (-5410 1410);
FORCEPROP 2 LASTPIN (-5400 1500) $PN AD47
J 2
(-5410 1510);
DISPLAY 0.617021 (-5410 1510);
PAINT ORANGE (-5410 1510);
FORCEPROP 2 LASTPIN (-5400 1700) $PN Y65
J 2
(-5410 1710);
DISPLAY 0.617021 (-5410 1710);
PAINT ORANGE (-5410 1710);
FORCEPROP 2 LASTPIN (-5400 1750) $PN Y23
J 2
(-5410 1760);
DISPLAY 0.617021 (-5410 1760);
PAINT ORANGE (-5410 1760);
FORCEPROP 2 LASTPIN (-5400 1950) $PN V65
J 2
(-5410 1960);
DISPLAY 0.617021 (-5410 1960);
PAINT ORANGE (-5410 1960);
FORCEPROP 2 LASTPIN (-5400 2000) $PN U66
J 2
(-5410 2010);
DISPLAY 0.617021 (-5410 2010);
PAINT ORANGE (-5410 2010);
FORCEPROP 2 LASTPIN (-5400 2050) $PN T67
J 2
(-5410 2060);
DISPLAY 0.617021 (-5410 2060);
PAINT ORANGE (-5410 2060);
FORCEPROP 2 LASTPIN (-5400 2100) $PN R66
J 2
(-5410 2110);
DISPLAY 0.617021 (-5410 2110);
PAINT ORANGE (-5410 2110);
FORCEPROP 2 LASTPIN (-5400 2150) $PN R62
J 2
(-5410 2160);
DISPLAY 0.617021 (-5410 2160);
PAINT ORANGE (-5410 2160);
FORCEPROP 2 LASTPIN (-5400 2200) $PN P65
J 2
(-5410 2210);
DISPLAY 0.617021 (-5410 2210);
PAINT ORANGE (-5410 2210);
FORCEPROP 2 LASTPIN (-5400 2250) $PN M63
J 2
(-5410 2260);
DISPLAY 0.617021 (-5410 2260);
PAINT ORANGE (-5410 2260);
FORCEPROP 2 LASTPIN (-5400 2300) $PN K61
J 2
(-5410 2310);
DISPLAY 0.617021 (-5410 2310);
PAINT ORANGE (-5410 2310);
FORCEPROP 2 LASTPIN (-5400 2350) $PN J62
J 2
(-5410 2360);
DISPLAY 0.617021 (-5410 2360);
PAINT ORANGE (-5410 2360);
FORCEPROP 2 LASTPIN (-5400 2400) $PN J46
J 2
(-5410 2410);
DISPLAY 0.617021 (-5410 2410);
PAINT ORANGE (-5410 2410);
FORCEPROP 2 LASTPIN (-5400 2450) $PN H85
J 2
(-5410 2460);
DISPLAY 0.617021 (-5410 2460);
PAINT ORANGE (-5410 2460);
FORCEPROP 2 LASTPIN (-5400 2500) $PN H83
J 2
(-5410 2510);
DISPLAY 0.617021 (-5410 2510);
PAINT ORANGE (-5410 2510);
FORCEPROP 2 LASTPIN (-5400 2550) $PN H1
J 2
(-5410 2560);
DISPLAY 0.617021 (-5410 2560);
PAINT ORANGE (-5410 2560);
FORCEPROP 2 LASTPIN (-5400 2600) $PN G84
J 2
(-5410 2610);
DISPLAY 0.617021 (-5410 2610);
PAINT ORANGE (-5410 2610);
FORCEPROP 2 LASTPIN (-5400 2650) $PN G64
J 2
(-5410 2660);
DISPLAY 0.617021 (-5410 2660);
PAINT ORANGE (-5410 2660);
FORCEPROP 2 LASTPIN (-5400 2700) $PN G2
J 2
(-5410 2710);
DISPLAY 0.617021 (-5410 2710);
PAINT ORANGE (-5410 2710);
FORCEPROP 2 LASTPIN (-5400 2800) $PN F83
J 2
(-5410 2810);
DISPLAY 0.617021 (-5410 2810);
PAINT ORANGE (-5410 2810);
FORCEPROP 2 LASTPIN (-5400 2850) $PN F65
J 2
(-5410 2860);
DISPLAY 0.617021 (-5410 2860);
PAINT ORANGE (-5410 2860);
FORCEPROP 2 LASTPIN (-5400 2950) $PN F23
J 2
(-5410 2960);
DISPLAY 0.617021 (-5410 2960);
PAINT ORANGE (-5410 2960);
FORCEPROP 2 LASTPIN (-5400 3000) $PN F3
J 2
(-5410 3010);
DISPLAY 0.617021 (-5410 3010);
PAINT ORANGE (-5410 3010);
FORCEPROP 2 LASTPIN (-5400 3050) $PN E84
J 2
(-5410 3060);
DISPLAY 0.617021 (-5410 3060);
PAINT ORANGE (-5410 3060);
FORCEPROP 2 LASTPIN (-5400 3200) $PN E4
J 2
(-5410 3210);
DISPLAY 0.617021 (-5410 3210);
PAINT ORANGE (-5410 3210);
FORCEPROP 2 LASTPIN (-5400 3250) $PN E2
J 2
(-5410 3260);
DISPLAY 0.617021 (-5410 3260);
PAINT ORANGE (-5410 3260);
FORCEPROP 2 LASTPIN (-5400 3300) $PN D83
J 2
(-5410 3310);
DISPLAY 0.617021 (-5410 3310);
PAINT ORANGE (-5410 3310);
FORCEPROP 2 LASTPIN (-5400 3350) $PN D65
J 2
(-5410 3360);
DISPLAY 0.617021 (-5410 3360);
PAINT ORANGE (-5410 3360);
FORCEPROP 2 LASTPIN (-5400 3400) $PN D17
J 2
(-5410 3410);
DISPLAY 0.617021 (-5410 3410);
PAINT ORANGE (-5410 3410);
FORCEPROP 2 LASTPIN (-5400 3450) $PN D5
J 2
(-5410 3460);
DISPLAY 0.617021 (-5410 3460);
PAINT ORANGE (-5410 3460);
FORCEPROP 2 LASTPIN (-5400 3500) $PN C82
J 2
(-5410 3510);
DISPLAY 0.617021 (-5410 3510);
PAINT ORANGE (-5410 3510);
FORCEPROP 2 LASTPIN (-5400 3650) $PN C18
J 2
(-5410 3660);
DISPLAY 0.617021 (-5410 3660);
PAINT ORANGE (-5410 3660);
FORCEPROP 2 LASTPIN (-5400 3700) $PN C6
J 2
(-5410 3710);
DISPLAY 0.617021 (-5410 3710);
PAINT ORANGE (-5410 3710);
FORCEPROP 2 LASTPIN (-5400 3750) $PN B81
J 2
(-5410 3760);
DISPLAY 0.617021 (-5410 3760);
PAINT ORANGE (-5410 3760);
FORCEPROP 2 LASTPIN (-5400 3800) $PN B77
J 2
(-5410 3810);
DISPLAY 0.617021 (-5410 3810);
PAINT ORANGE (-5410 3810);
FORCEPROP 2 LASTPIN (-5400 3850) $PN B17
J 2
(-5410 3860);
DISPLAY 0.617021 (-5410 3860);
PAINT ORANGE (-5410 3860);
FORCEPROP 2 LASTPIN (-5400 3900) $PN B15
J 2
(-5410 3910);
DISPLAY 0.617021 (-5410 3910);
PAINT ORANGE (-5410 3910);
FORCEPROP 2 LASTPIN (-5400 3950) $PN B13
J 2
(-5410 3960);
DISPLAY 0.617021 (-5410 3960);
PAINT ORANGE (-5410 3960);
FORCEPROP 2 LASTPIN (-5400 4050) $PN B7
J 2
(-5410 4060);
DISPLAY 0.617021 (-5410 4060);
PAINT ORANGE (-5410 4060);
FORCEPROP 2 LASTPIN (-5400 4100) $PN B3
J 2
(-5410 4110);
DISPLAY 0.617021 (-5410 4110);
PAINT ORANGE (-5410 4110);
FORCEPROP 2 LASTPIN (-5400 4150) $PN A24
J 2
(-5410 4160);
DISPLAY 0.617021 (-5410 4160);
PAINT ORANGE (-5410 4160);
FORCEPROP 2 LASTPIN (-5400 4200) $PN A16
J 2
(-5410 4210);
DISPLAY 0.617021 (-5410 4210);
PAINT ORANGE (-5410 4210);
FORCEPROP 2 LASTPIN (-5400 4250) $PN A14
J 2
(-5410 4260);
DISPLAY 0.617021 (-5410 4260);
PAINT ORANGE (-5410 4260);
FORCEPROP 2 LASTPIN (-5400 4300) $PN A6
J 2
(-5410 4310);
DISPLAY 0.617021 (-5410 4310);
PAINT ORANGE (-5410 4310);
FORCEPROP 2 LASTPIN (-5400 4350) $PN A4
J 2
(-5410 4360);
DISPLAY 0.617021 (-5410 4360);
PAINT ORANGE (-5410 4360);
FORCEPROP 2 LASTPIN (-2900 3100) $PN AF45
J 0
(-2890 3110);
DISPLAY 0.617021 (-2890 3110);
PAINT ORANGE (-2890 3110);
FORCEPROP 2 LASTPIN (-2900 3000) $PN AM13
J 0
(-2890 3010);
DISPLAY 0.617021 (-2890 3010);
PAINT ORANGE (-2890 3010);
FORCEPROP 2 LASTPIN (-2900 2950) $PN AN12
J 0
(-2890 2960);
DISPLAY 0.617021 (-2890 2960);
PAINT ORANGE (-2890 2960);
FORCEPROP 2 LASTPIN (-2900 2350) $PN AN14
J 0
(-2890 2360);
DISPLAY 0.617021 (-2890 2360);
PAINT ORANGE (-2890 2360);
FORCEPROP 2 LASTPIN (-5400 1600) $PN AY13
J 2
(-5410 1610);
DISPLAY 0.617021 (-5410 1610);
PAINT ORANGE (-5410 1610);
FORCEPROP 1 LAST MATERIAL IC
J 0
(-5350 4550);
DISPLAY 0.617021 (-5350 4550);
PAINT SKYBLUE (-5350 4550);
FORCEPROP 1 LAST PART_NUMBER TBD
J 0
(-5350 550);
DISPLAY 0.617021 (-5350 550);
PAINT BLUE (-5350 550);
FORCEPROP 1 LAST LOCATION U5D1
J 0
(-5350 4600);
DISPLAY 0.617021 (-5350 4600);
PAINT AQUA (-5350 4600);
FORCEPROP 2 LASTPIN (-2900 2550) $PN AK59
J 0
(-2890 2560);
DISPLAY 0.617021 (-2890 2560);
PAINT ORANGE (-2890 2560);
FORCEPROP 2 LASTPIN (-2900 2600) $PN AK57
J 0
(-2890 2610);
DISPLAY 0.617021 (-2890 2610);
PAINT ORANGE (-2890 2610);
FORCEPROP 2 LASTPIN (-2900 3050) $PN AG46
J 0
(-2890 3060);
DISPLAY 0.617021 (-2890 3060);
PAINT ORANGE (-2890 3060);
FORCEPROP 0 LAST ROOM CPU0
J 0
(-5350 4700);
DISPLAY 1.021277 (-5350 4700);
PAINT ORANGE (-5350 4700);
DISPLAY INVISIBLE (-5350 4700);
FORCEPROP 1 LAST PATH I204
J 0
(-4150 4550);
PAINT GREEN (-4150 4550);
DISPLAY INVISIBLE (-4150 4550);
FORCEPROP 2 LAST CDS_LOCATION U5D1
J 0
(-5350 4600);
DISPLAY 0.617021 (-5350 4600);
PAINT AQUA (-5350 4600);
DISPLAY INVISIBLE (-5350 4600);
FORCEPROP 2 LAST SEC 2
J 0
(-5350 4650);
DISPLAY 0.680851 (-5350 4650);
PAINT MONO (-5350 4650);
DISPLAY INVISIBLE (-5350 4650);
FORCEPROP 2 LAST SEC_TYPE BGA1
J 0
(-5350 4650);
DISPLAY 1.021277 (-5350 4650);
PAINT ORANGE (-5350 4650);
DISPLAY INVISIBLE (-5350 4650);
FORCEPROP 2 LAST CDS_LIB chpset_lib
J 0
(-4150 2550);
PAINT ORANGE (-4150 2550);
DISPLAY INVISIBLE (-4150 2550);
FORCEPROP 1 LAST PACK_TYPE BGA1
J 0
(-5350 4650);
PAINT SKYBLUE (-5350 4650);
DISPLAY INVISIBLE (-5350 4650);
FORCEADD OFFPAGE..2
R 2
(-7100 1750);
FORCEPROP 2 LAST $XR3 145 
J 0
(-7715 1750);
DISPLAY 0.638298 (-7715 1750);
PAINT MONO (-7715 1750);
FORCEPROP 2 LAST $XR2 120 
J 0
(-7595 1750);
DISPLAY 0.638298 (-7595 1750);
PAINT MONO (-7595 1750);
FORCEPROP 2 LAST $XR1 118 
J 0
(-7475 1750);
DISPLAY 0.638298 (-7475 1750);
PAINT MONO (-7475 1750);
FORCEPROP 2 LAST $XR0 133 
J 0
(-7355 1750);
DISPLAY 0.638298 (-7355 1750);
PAINT MONO (-7355 1750);
FORCEPROP 2 LAST PATH I205
J 2
(-7275 1825);
DISPLAY 1.021277 (-7275 1825);
PAINT ORANGE (-7275 1825);
DISPLAY INVISIBLE (-7275 1825);
FORCEPROP 2 LAST CDS_LIB mstr_standard
J 2
(-7100 1750);
PAINT ORANGE (-7100 1750);
DISPLAY INVISIBLE (-7100 1750);
FORCEPROP 1 LAST OFFPAGE TRUE
J 2
(-7425 1625);
DISPLAY 0.489362 (-7425 1625);
PAINT GREEN (-7425 1625);
DISPLAY INVISIBLE (-7425 1625);
FORCEPROP 1 LAST COMMENT_BODY TRUE
J 2
(-7055 1655);
DISPLAY 0.936170 (-7055 1655);
PAINT PEACH (-7055 1655);
DISPLAY INVISIBLE (-7055 1655);
FORCEADD OFFPAGE..4
(-1700 3250);
FORCEPROP 2 LAST $XR0 194 
J 0
(-1514 3250);
DISPLAY 0.638298 (-1514 3250);
PAINT MONO (-1514 3250);
FORCEPROP 2 LAST CDS_LIB mstr_standard
J 0
(-1700 3250);
PAINT ORANGE (-1700 3250);
DISPLAY INVISIBLE (-1700 3250);
FORCEPROP 2 LAST PATH I206
J 0
(-1525 3325);
DISPLAY 1.021277 (-1525 3325);
PAINT ORANGE (-1525 3325);
DISPLAY INVISIBLE (-1525 3325);
FORCEPROP 1 LAST OFFPAGE TRUE
J 0
(-1375 3125);
DISPLAY 0.680851 (-1375 3125);
PAINT GREEN (-1375 3125);
DISPLAY INVISIBLE (-1375 3125);
FORCEPROP 1 LAST COMMENT_BODY TRUE
J 0
(-1725 3150);
DISPLAY 0.680851 (-1725 3150);
PAINT PEACH (-1725 3150);
DISPLAY INVISIBLE (-1725 3150);
FORCEADD OFFPAGE..4
(-1700 2200);
FORCEPROP 2 LAST $XR0 194 
J 0
(-1514 2200);
DISPLAY 0.638298 (-1514 2200);
PAINT MONO (-1514 2200);
FORCEPROP 2 LAST PATH I207
J 0
(-1525 2275);
DISPLAY 1.021277 (-1525 2275);
PAINT ORANGE (-1525 2275);
DISPLAY INVISIBLE (-1525 2275);
FORCEPROP 2 LAST CDS_LIB mstr_standard
J 0
(-1700 2200);
PAINT ORANGE (-1700 2200);
DISPLAY INVISIBLE (-1700 2200);
FORCEPROP 1 LAST OFFPAGE TRUE
J 0
(-1375 2075);
DISPLAY 0.680851 (-1375 2075);
PAINT GREEN (-1375 2075);
DISPLAY INVISIBLE (-1375 2075);
FORCEPROP 1 LAST COMMENT_BODY TRUE
J 0
(-1725 2100);
DISPLAY 0.680851 (-1725 2100);
PAINT PEACH (-1725 2100);
DISPLAY INVISIBLE (-1725 2100);
FORCEADD DESIGN_NOTE..1
(-4900 475);
FORCEPROP 0 LAST L1 CPU SYMBOLS 1-30 ARE PRELIMINARY AND SUBJECT TO CHANGE
J 0
(-5100 350);
DISPLAY 1.021277 (-5100 350);
PAINT ORANGE (-5100 350);
FORCEPROP 2 LAST CDS_LIB mstr_symbols
J 0
(-4900 475);
PAINT ORANGE (-4900 475);
DISPLAY INVISIBLE (-4900 475);
FORCEPROP 1 LAST COMMENT_BODY TRUE
J 0
(-4875 575);
DISPLAY 0.978723 (-4875 575);
PAINT ORANGE (-4875 575);
DISPLAY INVISIBLE (-4875 575);
FORCEADD INTEL_CORP_BPAGE..1
(0 0);
FORCEPROP 1 LAST CDS_CON_LAST_MODIFIED Fri Jun 16 17:48:09 2017
J 0
(-1425 325);
DISPLAY 1.340426 (-1425 325);
PAINT GREEN (-1425 325);
DISPLAY INVISIBLE (-1425 325);
FORCEPROP 1 LAST CUSTOM_TXT_CDS <CURRENT_DESIGN_SHEET> OF <TOTAL_DESIGN_SHEETS>
J 0
(-500 25);
PAINT ORANGE (-500 25);
FORCEPROP 1 LAST CUSTOM_TXT_CDS <CON_LAST_MODIFIED>
J 0
(-4000 100);
PAINT ORANGE (-4000 100);
FORCEPROP 2 LAST CUSTOM_TXT_CDS <XR_PAGE_TITLE>
J 0
(-7890 5250);
DISPLAY 0.638298 (-7890 5250);
PAINT PINK (-7890 5250);
DISPLAY INVISIBLE (-7890 5250);
FORCEPROP 1 LAST SCH_TITLE SKYLAKE - SKT0 - 2 OF 21
J 0
(-7950 50);
DISPLAY 1.212766 (-7950 50);
PAINT GREEN (-7950 50);
FORCEPROP 2 LAST CDS_LIB mstr_symbols
J 0
(0 0);
PAINT ORANGE (0 0);
DISPLAY INVISIBLE (0 0);
FORCEPROP 2 LAST PAGE_BORDER TRUE
J 0
(-7890 5250);
DISPLAY 0.851064 (-7890 5250);
PAINT PINK (-7890 5250);
DISPLAY INVISIBLE (-7890 5250);
FORCEPROP 1 LAST COMMENT_BODY TRUE
J 0
(12 12);
DISPLAY 0.638298 (12 12);
PAINT GREEN (12 12);
DISPLAY INVISIBLE (12 12);
FORCEPROP 2 LAST CDS_XR_PAGE_TITLE CR-22 : @BASEBOARD_FAB2_LIB.BASEBOARD_FAB2(SCH_1):PAGE22
J 0
(-7890 5250);
DISPLAY 0.638298 (-7890 5250);
PAINT PINK (-7890 5250);
DISPLAY INVISIBLE (-7890 5250);
FORCEADD PRELIM..10
(-3940 2615);
PAINT GRAY (-3940 2615);
FORCEPROP 2 LAST CDS_LIB mstr_misc
J 0
(-3940 2615);
PAINT ORANGE (-3940 2615);
DISPLAY INVISIBLE (-3940 2615);
FORCEPROP 1 LAST COMMENT_BODY TRUE
J 0
(-3940 2615);
PAINT ORANGE (-3940 2615);
DISPLAY INVISIBLE (-3940 2615);
FORCEADD DESIGN_NOTE..1
(-700 1725);
FORCEPROP 0 LAST L1 CLKS USED FOR DEBUG ONLY
J 0
(-875 1600);
DISPLAY 0.808511 (-875 1600);
PAINT ORANGE (-875 1600);
FORCEPROP 2 LAST CDS_LIB mstr_symbols
J 0
(-700 1725);
PAINT ORANGE (-700 1725);
DISPLAY INVISIBLE (-700 1725);
FORCEPROP 1 LAST COMMENT_BODY TRUE
J 0
(-675 1825);
DISPLAY 0.978723 (-675 1825);
PAINT ORANGE (-675 1825);
DISPLAY INVISIBLE (-675 1825);
WIRE 16 -1 (-300 2550)(-300 2500);
WIRE 16 -1 (-575 2550)(-300 2550);
WIRE 16 -1 (-300 2675)(-300 2550);
WIRE 16 -1 (-575 2675)(-575 2550);
WIRE 16 -1 (-1100 2275)(-1100 1650);
WIRE 16 -1 (-1100 1500)(-1100 1650);
WIRE 16 -1 (-2900 1650)(-1100 1650);
WIRE 16 -1 (-1100 1100)(-1100 1500);
WIRE 16 -1 (-2900 1500)(-1100 1500);
WIRE 16 -1 (-2750 1100)(-1100 1100);
WIRE 16 -1 (-1100 900)(-1100 1100);
WIRE 16 -1 (-2750 900)(-1100 900);
WIRE 16 -1 (-2750 1150)(-2750 1100);
WIRE 16 -1 (-2900 1100)(-2750 1100);
WIRE 16 -1 (-2750 1200)(-2750 1150);
WIRE 16 -1 (-2900 1150)(-2750 1150);
WIRE 16 -1 (-2750 950)(-2750 900);
WIRE 16 -1 (-2900 900)(-2750 900);
WIRE 16 -1 (-2900 950)(-2750 950);
WIRE 16 -1 (-2750 1300)(-2750 1200);
WIRE 16 -1 (-2900 1200)(-2750 1200);
WIRE 16 -1 (-2900 1300)(-2750 1300);
WIRE 16 -1 (-7300 4250)(-7300 4425);
WIRE 16 -1 (-7300 3950)(-7300 4250);
WIRE 16 -1 (-5575 4250)(-7300 4250);
WIRE 16 -1 (-5575 4200)(-5575 4250);
WIRE 16 -1 (-5400 4250)(-5575 4250);
WIRE 16 -1 (-5575 3950)(-7300 3950);
WIRE 16 -1 (-5575 3900)(-5575 3950);
WIRE 16 -1 (-5400 3950)(-5575 3950);
WIRE 16 -1 (-5400 4200)(-5575 4200);
WIRE 16 -1 (-5575 3850)(-5575 3900);
WIRE 16 -1 (-5400 3900)(-5575 3900);
WIRE 16 -1 (-5400 3850)(-5575 3850);
WIRE 16 -1 (-5400 3500)(-6450 3500);
FORCEPROP 2 LAST SIG_NAME TP_CPU0_RSVD_288
J 0
(-6425 3510);
DISPLAY 0.617021 (-6425 3510);
PAINT ORANGE (-6425 3510);
FORCEPROP 2 LASTPROP $XRERR UNIQUE?
J 0
(-6690 3500);
DISPLAY 0.638298 (-6690 3500);
PAINT MONO (-6690 3500);
DISPLAY INVISIBLE (-6690 3500);
WIRE 16 -1 (-1750 2600)(-2900 2600);
FORCEPROP 2 LAST SIG_NAME TP_CPU0_RSVD_219
J 0
(-2700 2610);
DISPLAY 0.617021 (-2700 2610);
PAINT ORANGE (-2700 2610);
FORCEPROP 2 LASTPROP $XRERR UNIQUE?
J 0
(-1720 2600);
DISPLAY 0.638298 (-1720 2600);
PAINT MONO (-1720 2600);
DISPLAY INVISIBLE (-1720 2600);
WIRE 16 -1 (-5400 1150)(-6450 1150);
FORCEPROP 2 LAST SIG_NAME TP_CPU0_RSVD_248
J 0
(-6425 1160);
DISPLAY 0.617021 (-6425 1160);
PAINT ORANGE (-6425 1160);
FORCEPROP 2 LASTPROP $XRERR UNIQUE?
J 0
(-6690 1150);
DISPLAY 0.638298 (-6690 1150);
PAINT MONO (-6690 1150);
DISPLAY INVISIBLE (-6690 1150);
WIRE 16 -1 (-1750 1750)(-2900 1750);
FORCEPROP 2 LAST SIG_NAME TP_CPU0_RSVD_211
J 0
(-2700 1760);
DISPLAY 0.617021 (-2700 1760);
PAINT ORANGE (-2700 1760);
FORCEPROP 2 LASTPROP $XRERR UNIQUE?
J 0
(-1720 1750);
DISPLAY 0.638298 (-1720 1750);
PAINT MONO (-1720 1750);
DISPLAY INVISIBLE (-1720 1750);
WIRE 16 -1 (-1750 3350)(-2900 3350);
FORCEPROP 2 LAST SIG_NAME TP_CPU0_RSVD_223
J 0
(-2700 3360);
DISPLAY 0.617021 (-2700 3360);
PAINT ORANGE (-2700 3360);
FORCEPROP 2 LASTPROP $XRERR UNIQUE?
J 0
(-1720 3350);
DISPLAY 0.638298 (-1720 3350);
PAINT MONO (-1720 3350);
DISPLAY INVISIBLE (-1720 3350);
WIRE 16 -1 (-5400 4050)(-6450 4050);
FORCEPROP 2 LAST SIG_NAME TP_CPU0_RSVD_298
J 0
(-6425 4060);
DISPLAY 0.617021 (-6425 4060);
PAINT ORANGE (-6425 4060);
FORCEPROP 2 LASTPROP $XRERR UNIQUE?
J 0
(-6690 4050);
DISPLAY 0.638298 (-6690 4050);
PAINT MONO (-6690 4050);
DISPLAY INVISIBLE (-6690 4050);
WIRE 16 -1 (-1750 2500)(-2900 2500);
FORCEPROP 2 LAST SIG_NAME TP_CPU0_RSVD_217
J 0
(-2700 2510);
DISPLAY 0.617021 (-2700 2510);
PAINT ORANGE (-2700 2510);
FORCEPROP 2 LASTPROP $XRERR UNIQUE?
J 0
(-1720 2500);
DISPLAY 0.638298 (-1720 2500);
PAINT MONO (-1720 2500);
DISPLAY INVISIBLE (-1720 2500);
WIRE 16 -1 (-1750 2550)(-2900 2550);
FORCEPROP 2 LAST SIG_NAME TP_CPU0_RSVD_218
J 0
(-2700 2560);
DISPLAY 0.617021 (-2700 2560);
PAINT ORANGE (-2700 2560);
FORCEPROP 2 LASTPROP $XRERR UNIQUE?
J 0
(-1720 2550);
DISPLAY 0.638298 (-1720 2550);
PAINT MONO (-1720 2550);
DISPLAY INVISIBLE (-1720 2550);
WIRE 16 -1 (-1750 2650)(-2900 2650);
FORCEPROP 2 LAST SIG_NAME H_CPU0_FIVR_FAULT_G
J 0
(-2700 2660);
DISPLAY 0.617021 (-2700 2660);
PAINT ORANGE (-2700 2660);
WIRE 16 -1 (-1750 2700)(-2900 2700);
FORCEPROP 2 LAST SIG_NAME CLK_322M_OSC_CPU0_RC_DP
J 0
(-2710 2710);
DISPLAY 0.617021 (-2710 2710);
PAINT ORANGE (-2710 2710);
WIRE 16 -1 (-1750 2350)(-2900 2350);
FORCEPROP 2 LAST SIG_NAME TP_CPU0_RSVD_TEST_5
J 0
(-2700 2360);
DISPLAY 0.617021 (-2700 2360);
PAINT ORANGE (-2700 2360);
FORCEPROP 2 LASTPROP $XRERR UNIQUE?
J 0
(-1720 2350);
DISPLAY 0.638298 (-1720 2350);
PAINT MONO (-1720 2350);
DISPLAY INVISIBLE (-1720 2350);
WIRE 16 -1 (-1750 2450)(-2900 2450);
FORCEPROP 2 LAST SIG_NAME CPU_XDP_PRESENT_N
J 0
(-2700 2460);
DISPLAY 0.617021 (-2700 2460);
PAINT ORANGE (-2700 2460);
WIRE 16 -1 (-1750 1800)(-2900 1800);
FORCEPROP 2 LAST SIG_NAME TP_CPU0_RSVD_212
J 0
(-2700 1810);
DISPLAY 0.617021 (-2700 1810);
PAINT ORANGE (-2700 1810);
FORCEPROP 2 LASTPROP $XRERR UNIQUE?
J 0
(-1720 1800);
DISPLAY 0.638298 (-1720 1800);
PAINT MONO (-1720 1800);
DISPLAY INVISIBLE (-1720 1800);
WIRE 16 -1 (-1750 1850)(-2900 1850);
FORCEPROP 2 LAST SIG_NAME CLK_322M_OSC_CPU0_RC_DN
J 0
(-2710 1860);
DISPLAY 0.617021 (-2710 1860);
PAINT ORANGE (-2710 1860);
WIRE 16 -1 (-1750 2000)(-2900 2000);
FORCEPROP 2 LAST SIG_NAME TP_CPU0_RSVD_214
J 0
(-2700 2010);
DISPLAY 0.617021 (-2700 2010);
PAINT ORANGE (-2700 2010);
FORCEPROP 2 LASTPROP $XRERR UNIQUE?
J 0
(-1720 2000);
DISPLAY 0.638298 (-1720 2000);
PAINT MONO (-1720 2000);
DISPLAY INVISIBLE (-1720 2000);
WIRE 16 -1 (-1750 2050)(-2900 2050);
FORCEPROP 2 LAST SIG_NAME PD_CPU0_DMIMODE_OVERRIDE
J 0
(-2685 2060);
DISPLAY 0.638298 (-2685 2060);
PAINT ORANGE (-2685 2060);
WIRE 16 -1 (-1750 2250)(-2900 2250);
FORCEPROP 2 LAST SIG_NAME TP_CPU0_RSVD_216
J 0
(-2700 2260);
DISPLAY 0.617021 (-2700 2260);
PAINT ORANGE (-2700 2260);
FORCEPROP 2 LASTPROP $XRERR UNIQUE?
J 0
(-1720 2250);
DISPLAY 0.638298 (-1720 2250);
PAINT MONO (-1720 2250);
DISPLAY INVISIBLE (-1720 2250);
WIRE 16 -1 (-1750 2850)(-2900 2850);
FORCEPROP 2 LAST SIG_NAME XDP_CPU_PWR_DEBUG_N
J 0
(-2700 2860);
DISPLAY 0.617021 (-2700 2860);
PAINT ORANGE (-2700 2860);
WIRE 16 -1 (-2900 2200)(-1750 2200);
FORCEPROP 2 LAST SIG_NAME VSENSE_P1V8MCP_CPU0_SKT_VRTN
J 0
(-2685 2210);
DISPLAY 0.638298 (-2685 2210);
PAINT ORANGE (-2685 2210);
WIRE 16 -1 (-1750 1700)(-2900 1700);
FORCEPROP 2 LAST SIG_NAME TP_CPU0_RSVD_210
J 0
(-2700 1710);
DISPLAY 0.617021 (-2700 1710);
PAINT ORANGE (-2700 1710);
FORCEPROP 2 LASTPROP $XRERR UNIQUE?
J 0
(-1720 1700);
DISPLAY 0.638298 (-1720 1700);
PAINT MONO (-1720 1700);
DISPLAY INVISIBLE (-1720 1700);
WIRE 16 -1 (-1750 1550)(-2900 1550);
FORCEPROP 2 LAST SIG_NAME TP_CPU0_RSVD_208
J 0
(-2700 1560);
DISPLAY 0.617021 (-2700 1560);
PAINT ORANGE (-2700 1560);
FORCEPROP 2 LASTPROP $XRERR UNIQUE?
J 0
(-1720 1550);
DISPLAY 0.638298 (-1720 1550);
PAINT MONO (-1720 1550);
DISPLAY INVISIBLE (-1720 1550);
WIRE 16 -1 (-1750 1450)(-2900 1450);
FORCEPROP 2 LAST SIG_NAME CLK_100M_CPU0_RC_REFCLK0_DP
J 0
(-2700 1460);
DISPLAY 0.617021 (-2700 1460);
PAINT ORANGE (-2700 1460);
WIRE 16 -1 (-1750 1400)(-2900 1400);
FORCEPROP 2 LAST SIG_NAME TP_CPU0_RSVD_205
J 0
(-2700 1410);
DISPLAY 0.617021 (-2700 1410);
PAINT ORANGE (-2700 1410);
FORCEPROP 2 LASTPROP $XRERR UNIQUE?
J 0
(-1720 1400);
DISPLAY 0.638298 (-1720 1400);
PAINT MONO (-1720 1400);
DISPLAY INVISIBLE (-1720 1400);
WIRE 16 -1 (-1750 1350)(-2900 1350);
FORCEPROP 2 LAST SIG_NAME TP_CPU0_RSVD_204
J 0
(-2700 1360);
DISPLAY 0.617021 (-2700 1360);
PAINT ORANGE (-2700 1360);
FORCEPROP 2 LASTPROP $XRERR UNIQUE?
J 0
(-1720 1350);
DISPLAY 0.638298 (-1720 1350);
PAINT MONO (-1720 1350);
DISPLAY INVISIBLE (-1720 1350);
WIRE 16 -1 (-5400 3250)(-6475 3250);
FORCEPROP 2 LAST SIG_NAME TP_CPU0_RSVD_283
J 0
(-6425 3260);
DISPLAY 0.617021 (-6425 3260);
PAINT ORANGE (-6425 3260);
FORCEPROP 2 LASTPROP $XRERR UNIQUE?
J 0
(-6715 3250);
DISPLAY 0.638298 (-6715 3250);
PAINT MONO (-6715 3250);
DISPLAY INVISIBLE (-6715 3250);
WIRE 16 -1 (-5400 3400)(-6450 3400);
FORCEPROP 2 LAST SIG_NAME TP_CPU0_RSVD_286
J 0
(-6425 3410);
DISPLAY 0.617021 (-6425 3410);
PAINT ORANGE (-6425 3410);
FORCEPROP 2 LASTPROP $XRERR UNIQUE?
J 0
(-6690 3400);
DISPLAY 0.638298 (-6690 3400);
PAINT MONO (-6690 3400);
DISPLAY INVISIBLE (-6690 3400);
WIRE 16 -1 (-1750 3650)(-2900 3650);
FORCEPROP 2 LAST SIG_NAME TP_CPU0_RSVD_228
J 0
(-2700 3660);
DISPLAY 0.617021 (-2700 3660);
PAINT ORANGE (-2700 3660);
FORCEPROP 2 LASTPROP $XRERR UNIQUE?
J 0
(-1720 3650);
DISPLAY 0.638298 (-1720 3650);
PAINT MONO (-1720 3650);
DISPLAY INVISIBLE (-1720 3650);
WIRE 16 -1 (-1750 4100)(-2900 4100);
FORCEPROP 2 LAST SIG_NAME TP_CPU0_RSVD_236
J 0
(-2700 4110);
DISPLAY 0.617021 (-2700 4110);
PAINT ORANGE (-2700 4110);
FORCEPROP 2 LASTPROP $XRERR UNIQUE?
J 0
(-1720 4100);
DISPLAY 0.638298 (-1720 4100);
PAINT MONO (-1720 4100);
DISPLAY INVISIBLE (-1720 4100);
WIRE 16 -1 (-1750 3900)(-2900 3900);
FORCEPROP 2 LAST SIG_NAME TP_CPU0_RSVD_233
J 0
(-2700 3910);
DISPLAY 0.617021 (-2700 3910);
PAINT ORANGE (-2700 3910);
FORCEPROP 2 LASTPROP $XRERR UNIQUE?
J 0
(-1720 3900);
DISPLAY 0.638298 (-1720 3900);
PAINT MONO (-1720 3900);
DISPLAY INVISIBLE (-1720 3900);
WIRE 16 -1 (-1750 3850)(-2900 3850);
FORCEPROP 2 LAST SIG_NAME TP_CPU0_RSVD_232
J 0
(-2700 3860);
DISPLAY 0.617021 (-2700 3860);
PAINT ORANGE (-2700 3860);
FORCEPROP 2 LASTPROP $XRERR UNIQUE?
J 0
(-1720 3850);
DISPLAY 0.638298 (-1720 3850);
PAINT MONO (-1720 3850);
DISPLAY INVISIBLE (-1720 3850);
WIRE 16 -1 (-1750 3800)(-2900 3800);
FORCEPROP 2 LAST SIG_NAME TP_CPU0_RSVD_231
J 0
(-2700 3810);
DISPLAY 0.617021 (-2700 3810);
PAINT ORANGE (-2700 3810);
FORCEPROP 2 LASTPROP $XRERR UNIQUE?
J 0
(-1720 3800);
DISPLAY 0.638298 (-1720 3800);
PAINT MONO (-1720 3800);
DISPLAY INVISIBLE (-1720 3800);
WIRE 16 -1 (-7050 1750)(-5400 1750);
FORCEPROP 2 LAST SIG_NAME FM_CPU0_RC_ERROR_N
J 0
(-7000 1760);
DISPLAY 0.617021 (-7000 1760);
PAINT ORANGE (-7000 1760);
WIRE 16 -1 (-6450 1700)(-5400 1700);
FORCEPROP 2 LAST SIG_NAME TP_CPU0_RSVD_256
J 0
(-6425 1710);
DISPLAY 0.617021 (-6425 1710);
PAINT ORANGE (-6425 1710);
FORCEPROP 2 LASTPROP $XRERR UNIQUE?
J 0
(-6690 1700);
DISPLAY 0.638298 (-6690 1700);
PAINT MONO (-6690 1700);
DISPLAY INVISIBLE (-6690 1700);
WIRE 16 -1 (-5400 1600)(-6450 1600);
FORCEPROP 2 LAST SIG_NAME TP_CPU0_RSVD_TEST_11
J 0
(-6425 1610);
DISPLAY 0.617021 (-6425 1610);
PAINT ORANGE (-6425 1610);
FORCEPROP 2 LASTPROP $XRERR UNIQUE?
J 0
(-6690 1600);
DISPLAY 0.638298 (-6690 1600);
PAINT MONO (-6690 1600);
DISPLAY INVISIBLE (-6690 1600);
WIRE 16 -1 (-6450 1450)(-5400 1450);
FORCEPROP 2 LAST SIG_NAME TP_CPU0_RSVD_253
J 0
(-6425 1460);
DISPLAY 0.617021 (-6425 1460);
PAINT ORANGE (-6425 1460);
FORCEPROP 2 LASTPROP $XRERR UNIQUE?
J 0
(-6690 1450);
DISPLAY 0.638298 (-6690 1450);
PAINT MONO (-6690 1450);
DISPLAY INVISIBLE (-6690 1450);
WIRE 16 -1 (-6450 1500)(-5400 1500);
FORCEPROP 2 LAST SIG_NAME TP_CPU0_RSVD_254
J 0
(-6425 1510);
DISPLAY 0.617021 (-6425 1510);
PAINT ORANGE (-6425 1510);
FORCEPROP 2 LASTPROP $XRERR UNIQUE?
J 0
(-6690 1500);
DISPLAY 0.638298 (-6690 1500);
PAINT MONO (-6690 1500);
DISPLAY INVISIBLE (-6690 1500);
WIRE 16 -1 (-5400 4300)(-6450 4300);
FORCEPROP 2 LAST SIG_NAME TP_CPU0_RSVD_303
J 0
(-6425 4310);
DISPLAY 0.617021 (-6425 4310);
PAINT ORANGE (-6425 4310);
FORCEPROP 2 LASTPROP $XRERR UNIQUE?
J 0
(-6690 4300);
DISPLAY 0.638298 (-6690 4300);
PAINT MONO (-6690 4300);
DISPLAY INVISIBLE (-6690 4300);
WIRE 16 -1 (-5400 4350)(-6450 4350);
FORCEPROP 2 LAST SIG_NAME TP_CPU0_RSVD_304
J 0
(-6425 4360);
DISPLAY 0.617021 (-6425 4360);
PAINT ORANGE (-6425 4360);
FORCEPROP 2 LASTPROP $XRERR UNIQUE?
J 0
(-6690 4350);
DISPLAY 0.638298 (-6690 4350);
PAINT MONO (-6690 4350);
DISPLAY INVISIBLE (-6690 4350);
WIRE 16 -1 (-5400 3450)(-6450 3450);
FORCEPROP 2 LAST SIG_NAME TP_CPU0_RSVD_287
J 0
(-6425 3460);
DISPLAY 0.617021 (-6425 3460);
PAINT ORANGE (-6425 3460);
FORCEPROP 2 LASTPROP $XRERR UNIQUE?
J 0
(-6690 3450);
DISPLAY 0.638298 (-6690 3450);
PAINT MONO (-6690 3450);
DISPLAY INVISIBLE (-6690 3450);
WIRE 16 -1 (-5400 3350)(-6450 3350);
FORCEPROP 2 LAST SIG_NAME TP_CPU0_RSVD_285
J 0
(-6425 3360);
DISPLAY 0.617021 (-6425 3360);
PAINT ORANGE (-6425 3360);
FORCEPROP 2 LASTPROP $XRERR UNIQUE?
J 0
(-6690 3350);
DISPLAY 0.638298 (-6690 3350);
PAINT MONO (-6690 3350);
DISPLAY INVISIBLE (-6690 3350);
WIRE 16 -1 (-5400 3300)(-6450 3300);
FORCEPROP 2 LAST SIG_NAME TP_CPU0_RSVD_284
J 0
(-6425 3310);
DISPLAY 0.617021 (-6425 3310);
PAINT ORANGE (-6425 3310);
FORCEPROP 2 LASTPROP $XRERR UNIQUE?
J 0
(-6690 3300);
DISPLAY 0.638298 (-6690 3300);
PAINT MONO (-6690 3300);
DISPLAY INVISIBLE (-6690 3300);
WIRE 16 -1 (-5400 3200)(-6450 3200);
FORCEPROP 2 LAST SIG_NAME TP_CPU0_RSVD_282
J 0
(-6425 3210);
DISPLAY 0.617021 (-6425 3210);
PAINT ORANGE (-6425 3210);
FORCEPROP 2 LASTPROP $XRERR UNIQUE?
J 0
(-6690 3200);
DISPLAY 0.638298 (-6690 3200);
PAINT MONO (-6690 3200);
DISPLAY INVISIBLE (-6690 3200);
WIRE 16 -1 (-5400 2700)(-6475 2700);
FORCEPROP 2 LAST SIG_NAME TP_CPU0_RSVD_275
J 0
(-6425 2710);
DISPLAY 0.617021 (-6425 2710);
PAINT ORANGE (-6425 2710);
FORCEPROP 2 LASTPROP $XRERR UNIQUE?
J 0
(-6715 2700);
DISPLAY 0.638298 (-6715 2700);
PAINT MONO (-6715 2700);
DISPLAY INVISIBLE (-6715 2700);
WIRE 16 -1 (-5400 2300)(-6450 2300);
FORCEPROP 2 LAST SIG_NAME TP_CPU0_RSVD_267
J 0
(-6425 2310);
DISPLAY 0.617021 (-6425 2310);
PAINT ORANGE (-6425 2310);
FORCEPROP 2 LASTPROP $XRERR UNIQUE?
J 0
(-6690 2300);
DISPLAY 0.638298 (-6690 2300);
PAINT MONO (-6690 2300);
DISPLAY INVISIBLE (-6690 2300);
WIRE 16 -1 (-5400 2250)(-6450 2250);
FORCEPROP 2 LAST SIG_NAME TP_CPU0_RSVD_266
J 0
(-6425 2260);
DISPLAY 0.617021 (-6425 2260);
PAINT ORANGE (-6425 2260);
FORCEPROP 2 LASTPROP $XRERR UNIQUE?
J 0
(-6690 2250);
DISPLAY 0.638298 (-6690 2250);
PAINT MONO (-6690 2250);
DISPLAY INVISIBLE (-6690 2250);
WIRE 16 -1 (-5400 2100)(-6450 2100);
FORCEPROP 2 LAST SIG_NAME TP_CPU0_RSVD_263
J 0
(-6425 2110);
DISPLAY 0.617021 (-6425 2110);
PAINT ORANGE (-6425 2110);
FORCEPROP 2 LASTPROP $XRERR UNIQUE?
J 0
(-6690 2100);
DISPLAY 0.638298 (-6690 2100);
PAINT MONO (-6690 2100);
DISPLAY INVISIBLE (-6690 2100);
WIRE 16 -1 (-5400 2000)(-6450 2000);
FORCEPROP 2 LAST SIG_NAME TP_CPU0_RSVD_261
J 0
(-6425 2010);
DISPLAY 0.617021 (-6425 2010);
PAINT ORANGE (-6425 2010);
FORCEPROP 2 LASTPROP $XRERR UNIQUE?
J 0
(-6690 2000);
DISPLAY 0.638298 (-6690 2000);
PAINT MONO (-6690 2000);
DISPLAY INVISIBLE (-6690 2000);
WIRE 16 -1 (-6450 1850)(-5400 1850);
FORCEPROP 2 LAST SIG_NAME TP_CPU0_RSVD_259
J 0
(-6425 1860);
DISPLAY 0.617021 (-6425 1860);
PAINT ORANGE (-6425 1860);
FORCEPROP 2 LASTPROP $XRERR UNIQUE?
J 0
(-6690 1850);
DISPLAY 0.638298 (-6690 1850);
PAINT MONO (-6690 1850);
DISPLAY INVISIBLE (-6690 1850);
WIRE 16 -1 (-1750 800)(-2900 800);
FORCEPROP 2 LAST SIG_NAME TP_CPU0_RSVD_194
J 0
(-2700 810);
DISPLAY 0.617021 (-2700 810);
PAINT ORANGE (-2700 810);
FORCEPROP 2 LASTPROP $XRERR UNIQUE?
J 0
(-1720 800);
DISPLAY 0.638298 (-1720 800);
PAINT MONO (-1720 800);
DISPLAY INVISIBLE (-1720 800);
WIRE 16 -1 (-1750 850)(-2900 850);
FORCEPROP 2 LAST SIG_NAME CLK_100M_CPU0_RC_REFCLK0_DN
J 0
(-2700 860);
DISPLAY 0.617021 (-2700 860);
PAINT ORANGE (-2700 860);
WIRE 16 -1 (-1750 1000)(-2900 1000);
FORCEPROP 2 LAST SIG_NAME TP_CPU0_RSVD_198
J 0
(-2700 1010);
DISPLAY 0.617021 (-2700 1010);
PAINT ORANGE (-2700 1010);
FORCEPROP 2 LASTPROP $XRERR UNIQUE?
J 0
(-1720 1000);
DISPLAY 0.638298 (-1720 1000);
PAINT MONO (-1720 1000);
DISPLAY INVISIBLE (-1720 1000);
WIRE 16 -1 (-1750 1050)(-2900 1050);
FORCEPROP 2 LAST SIG_NAME TP_CPU0_RSVD_199
J 0
(-2700 1060);
DISPLAY 0.617021 (-2700 1060);
PAINT ORANGE (-2700 1060);
FORCEPROP 2 LASTPROP $XRERR UNIQUE?
J 0
(-1720 1050);
DISPLAY 0.638298 (-1720 1050);
PAINT MONO (-1720 1050);
DISPLAY INVISIBLE (-1720 1050);
WIRE 16 -1 (-2900 2950)(-1750 2950);
FORCEPROP 2 LAST SIG_NAME TP_CPU0_RSVD_TEST_4
J 0
(-2700 2960);
DISPLAY 0.617021 (-2700 2960);
PAINT ORANGE (-2700 2960);
FORCEPROP 2 LASTPROP $XRERR UNIQUE?
J 0
(-1720 2950);
DISPLAY 0.638298 (-1720 2950);
PAINT MONO (-1720 2950);
DISPLAY INVISIBLE (-1720 2950);
WIRE 16 -1 (-2900 3000)(-1750 3000);
FORCEPROP 2 LAST SIG_NAME TP_CPU0_RSVD_TEST_3
J 0
(-2700 3010);
DISPLAY 0.617021 (-2700 3010);
PAINT ORANGE (-2700 3010);
FORCEPROP 2 LASTPROP $XRERR UNIQUE?
J 0
(-1720 3000);
DISPLAY 0.638298 (-1720 3000);
PAINT MONO (-1720 3000);
DISPLAY INVISIBLE (-1720 3000);
WIRE 16 -1 (-575 3050)(-575 2875);
WIRE 16 -1 (-2900 3050)(-575 3050);
FORCEPROP 2 LAST SIG_NAME PD_CPU0_RSVD_TEST_2
J 0
(-2700 3060);
DISPLAY 0.617021 (-2700 3060);
PAINT ORANGE (-2700 3060);
FORCEPROP 2 LASTPROP $XRERR UNIQUE?
J 0
(-2940 3060);
DISPLAY 0.638298 (-2940 3060);
PAINT MONO (-2940 3060);
DISPLAY INVISIBLE (-2940 3060);
WIRE 16 -1 (-300 2875)(-300 3100);
WIRE 16 -1 (-2900 3100)(-300 3100);
FORCEPROP 2 LAST SIG_NAME PD_CPU0_RSVD_TEST_1
J 0
(-2700 3110);
DISPLAY 0.617021 (-2700 3110);
PAINT ORANGE (-2700 3110);
FORCEPROP 2 LASTPROP $XRERR UNIQUE?
J 0
(-2940 3110);
DISPLAY 0.638298 (-2940 3110);
PAINT MONO (-2940 3110);
DISPLAY INVISIBLE (-2940 3110);
WIRE 16 -1 (-2900 3250)(-1750 3250);
FORCEPROP 2 LAST SIG_NAME VSENSE_P1V8MCP_CPU0_SKT_VSEN
J 0
(-2685 3260);
DISPLAY 0.638298 (-2685 3260);
PAINT ORANGE (-2685 3260);
WIRE 16 -1 (-1750 3300)(-2900 3300);
FORCEPROP 2 LAST SIG_NAME TP_CPU0_RSVD_222
J 0
(-2700 3310);
DISPLAY 0.617021 (-2700 3310);
PAINT ORANGE (-2700 3310);
FORCEPROP 2 LASTPROP $XRERR UNIQUE?
J 0
(-1720 3300);
DISPLAY 0.638298 (-1720 3300);
PAINT MONO (-1720 3300);
DISPLAY INVISIBLE (-1720 3300);
WIRE 16 -1 (-1750 4350)(-2900 4350);
FORCEPROP 2 LAST SIG_NAME TP_CPU0_RSVD_241
J 0
(-2700 4360);
DISPLAY 0.617021 (-2700 4360);
PAINT ORANGE (-2700 4360);
FORCEPROP 2 LASTPROP $XRERR UNIQUE?
J 0
(-1720 4350);
DISPLAY 0.638298 (-1720 4350);
PAINT MONO (-1720 4350);
DISPLAY INVISIBLE (-1720 4350);
WIRE 16 -1 (-1750 4300)(-2900 4300);
FORCEPROP 2 LAST SIG_NAME TP_CPU0_RSVD_240
J 0
(-2700 4310);
DISPLAY 0.617021 (-2700 4310);
PAINT ORANGE (-2700 4310);
FORCEPROP 2 LASTPROP $XRERR UNIQUE?
J 0
(-1720 4300);
DISPLAY 0.638298 (-1720 4300);
PAINT MONO (-1720 4300);
DISPLAY INVISIBLE (-1720 4300);
WIRE 16 -1 (-1750 4250)(-2900 4250);
FORCEPROP 2 LAST SIG_NAME TP_CPU0_RSVD_239
J 0
(-2700 4260);
DISPLAY 0.617021 (-2700 4260);
PAINT ORANGE (-2700 4260);
FORCEPROP 2 LASTPROP $XRERR UNIQUE?
J 0
(-1720 4250);
DISPLAY 0.638298 (-1720 4250);
PAINT MONO (-1720 4250);
DISPLAY INVISIBLE (-1720 4250);
WIRE 16 -1 (-1750 4200)(-2900 4200);
FORCEPROP 2 LAST SIG_NAME TP_CPU0_RSVD_238
J 0
(-2700 4210);
DISPLAY 0.617021 (-2700 4210);
PAINT ORANGE (-2700 4210);
FORCEPROP 2 LASTPROP $XRERR UNIQUE?
J 0
(-1720 4200);
DISPLAY 0.638298 (-1720 4200);
PAINT MONO (-1720 4200);
DISPLAY INVISIBLE (-1720 4200);
WIRE 16 -1 (-1750 4150)(-2900 4150);
FORCEPROP 2 LAST SIG_NAME TP_CPU0_RSVD_237
J 0
(-2700 4160);
DISPLAY 0.617021 (-2700 4160);
PAINT ORANGE (-2700 4160);
FORCEPROP 2 LASTPROP $XRERR UNIQUE?
J 0
(-1720 4150);
DISPLAY 0.638298 (-1720 4150);
PAINT MONO (-1720 4150);
DISPLAY INVISIBLE (-1720 4150);
WIRE 16 -1 (-1750 4050)(-2900 4050);
FORCEPROP 2 LAST SIG_NAME TP_CPU0_RSVD_235
J 0
(-2700 4060);
DISPLAY 0.617021 (-2700 4060);
PAINT ORANGE (-2700 4060);
FORCEPROP 2 LASTPROP $XRERR UNIQUE?
J 0
(-1720 4050);
DISPLAY 0.638298 (-1720 4050);
PAINT MONO (-1720 4050);
DISPLAY INVISIBLE (-1720 4050);
WIRE 16 -1 (-1750 3950)(-2900 3950);
FORCEPROP 2 LAST SIG_NAME TP_CPU0_RSVD_234
J 0
(-2700 3960);
DISPLAY 0.617021 (-2700 3960);
PAINT ORANGE (-2700 3960);
FORCEPROP 2 LASTPROP $XRERR UNIQUE?
J 0
(-1720 3950);
DISPLAY 0.638298 (-1720 3950);
PAINT MONO (-1720 3950);
DISPLAY INVISIBLE (-1720 3950);
WIRE 16 -1 (-1750 3750)(-2900 3750);
FORCEPROP 2 LAST SIG_NAME TP_CPU0_RSVD_230
J 0
(-2700 3760);
DISPLAY 0.617021 (-2700 3760);
PAINT ORANGE (-2700 3760);
FORCEPROP 2 LASTPROP $XRERR UNIQUE?
J 0
(-1720 3750);
DISPLAY 0.638298 (-1720 3750);
PAINT MONO (-1720 3750);
DISPLAY INVISIBLE (-1720 3750);
WIRE 16 -1 (-1750 3700)(-2900 3700);
FORCEPROP 2 LAST SIG_NAME TP_CPU0_RSVD_229
J 0
(-2700 3710);
DISPLAY 0.617021 (-2700 3710);
PAINT ORANGE (-2700 3710);
FORCEPROP 2 LASTPROP $XRERR UNIQUE?
J 0
(-1720 3700);
DISPLAY 0.638298 (-1720 3700);
PAINT MONO (-1720 3700);
DISPLAY INVISIBLE (-1720 3700);
WIRE 16 -1 (-1750 3550)(-2900 3550);
FORCEPROP 2 LAST SIG_NAME TP_CPU0_RSVD_227
J 0
(-2700 3560);
DISPLAY 0.617021 (-2700 3560);
PAINT ORANGE (-2700 3560);
FORCEPROP 2 LASTPROP $XRERR UNIQUE?
J 0
(-1720 3550);
DISPLAY 0.638298 (-1720 3550);
PAINT MONO (-1720 3550);
DISPLAY INVISIBLE (-1720 3550);
WIRE 16 -1 (-1750 3500)(-2900 3500);
FORCEPROP 2 LAST SIG_NAME TP_CPU0_RSVD_226
J 0
(-2700 3510);
DISPLAY 0.617021 (-2700 3510);
PAINT ORANGE (-2700 3510);
FORCEPROP 2 LASTPROP $XRERR UNIQUE?
J 0
(-1720 3500);
DISPLAY 0.638298 (-1720 3500);
PAINT MONO (-1720 3500);
DISPLAY INVISIBLE (-1720 3500);
WIRE 16 -1 (-1750 3450)(-2900 3450);
FORCEPROP 2 LAST SIG_NAME TP_CPU0_RSVD_225
J 0
(-2700 3460);
DISPLAY 0.617021 (-2700 3460);
PAINT ORANGE (-2700 3460);
FORCEPROP 2 LASTPROP $XRERR UNIQUE?
J 0
(-1720 3450);
DISPLAY 0.638298 (-1720 3450);
PAINT MONO (-1720 3450);
DISPLAY INVISIBLE (-1720 3450);
WIRE 16 -1 (-1750 3400)(-2900 3400);
FORCEPROP 2 LAST SIG_NAME TP_CPU0_RSVD_224
J 0
(-2700 3410);
DISPLAY 0.617021 (-2700 3410);
PAINT ORANGE (-2700 3410);
FORCEPROP 2 LASTPROP $XRERR UNIQUE?
J 0
(-1720 3400);
DISPLAY 0.638298 (-1720 3400);
PAINT MONO (-1720 3400);
DISPLAY INVISIBLE (-1720 3400);
WIRE 16 -1 (-5400 3550)(-6450 3550);
FORCEPROP 2 LAST SIG_NAME TP_CPU0_RSVD_289
J 0
(-6425 3560);
DISPLAY 0.617021 (-6425 3560);
PAINT ORANGE (-6425 3560);
FORCEPROP 2 LASTPROP $XRERR UNIQUE?
J 0
(-6690 3550);
DISPLAY 0.638298 (-6690 3550);
PAINT MONO (-6690 3550);
DISPLAY INVISIBLE (-6690 3550);
WIRE 16 -1 (-6450 1950)(-5400 1950);
FORCEPROP 2 LAST SIG_NAME TP_CPU0_RSVD_260
J 0
(-6425 1960);
DISPLAY 0.617021 (-6425 1960);
PAINT ORANGE (-6425 1960);
FORCEPROP 2 LASTPROP $XRERR UNIQUE?
J 0
(-6690 1950);
DISPLAY 0.638298 (-6690 1950);
PAINT MONO (-6690 1950);
DISPLAY INVISIBLE (-6690 1950);
WIRE 16 -1 (-5400 2450)(-6450 2450);
FORCEPROP 2 LAST SIG_NAME TP_CPU0_RSVD_270
J 0
(-6425 2460);
DISPLAY 0.617021 (-6425 2460);
PAINT ORANGE (-6425 2460);
FORCEPROP 2 LASTPROP $XRERR UNIQUE?
J 0
(-6690 2450);
DISPLAY 0.638298 (-6690 2450);
PAINT MONO (-6690 2450);
DISPLAY INVISIBLE (-6690 2450);
WIRE 16 -1 (-5400 2400)(-6450 2400);
FORCEPROP 2 LAST SIG_NAME TP_CPU0_RSVD_269
J 0
(-6425 2410);
DISPLAY 0.617021 (-6425 2410);
PAINT ORANGE (-6425 2410);
FORCEPROP 2 LASTPROP $XRERR UNIQUE?
J 0
(-6690 2400);
DISPLAY 0.638298 (-6690 2400);
PAINT MONO (-6690 2400);
DISPLAY INVISIBLE (-6690 2400);
WIRE 16 -1 (-5400 2500)(-6450 2500);
FORCEPROP 2 LAST SIG_NAME TP_CPU0_RSVD_271
J 0
(-6425 2510);
DISPLAY 0.617021 (-6425 2510);
PAINT ORANGE (-6425 2510);
FORCEPROP 2 LASTPROP $XRERR UNIQUE?
J 0
(-6690 2500);
DISPLAY 0.638298 (-6690 2500);
PAINT MONO (-6690 2500);
DISPLAY INVISIBLE (-6690 2500);
WIRE 16 -1 (-5400 2600)(-6450 2600);
FORCEPROP 2 LAST SIG_NAME TP_CPU0_RSVD_273
J 0
(-6425 2610);
DISPLAY 0.617021 (-6425 2610);
PAINT ORANGE (-6425 2610);
FORCEPROP 2 LASTPROP $XRERR UNIQUE?
J 0
(-6690 2600);
DISPLAY 0.638298 (-6690 2600);
PAINT MONO (-6690 2600);
DISPLAY INVISIBLE (-6690 2600);
WIRE 16 -1 (-5400 2350)(-6450 2350);
FORCEPROP 2 LAST SIG_NAME TP_CPU0_RSVD_268
J 0
(-6425 2360);
DISPLAY 0.617021 (-6425 2360);
PAINT ORANGE (-6425 2360);
FORCEPROP 2 LASTPROP $XRERR UNIQUE?
J 0
(-6690 2350);
DISPLAY 0.638298 (-6690 2350);
PAINT MONO (-6690 2350);
DISPLAY INVISIBLE (-6690 2350);
WIRE 16 -1 (-5400 3650)(-6450 3650);
FORCEPROP 2 LAST SIG_NAME TP_CPU0_RSVD_290
J 0
(-6425 3660);
DISPLAY 0.617021 (-6425 3660);
PAINT ORANGE (-6425 3660);
FORCEPROP 2 LASTPROP $XRERR UNIQUE?
J 0
(-6690 3650);
DISPLAY 0.638298 (-6690 3650);
PAINT MONO (-6690 3650);
DISPLAY INVISIBLE (-6690 3650);
WIRE 16 -1 (-5400 3700)(-6450 3700);
FORCEPROP 2 LAST SIG_NAME TP_CPU0_RSVD_291
J 0
(-6425 3710);
DISPLAY 0.617021 (-6425 3710);
PAINT ORANGE (-6425 3710);
FORCEPROP 2 LASTPROP $XRERR UNIQUE?
J 0
(-6690 3700);
DISPLAY 0.638298 (-6690 3700);
PAINT MONO (-6690 3700);
DISPLAY INVISIBLE (-6690 3700);
WIRE 16 -1 (-5400 3750)(-6450 3750);
FORCEPROP 2 LAST SIG_NAME TP_CPU0_RSVD_292
J 0
(-6425 3760);
DISPLAY 0.617021 (-6425 3760);
PAINT ORANGE (-6425 3760);
FORCEPROP 2 LASTPROP $XRERR UNIQUE?
J 0
(-6690 3750);
DISPLAY 0.638298 (-6690 3750);
PAINT MONO (-6690 3750);
DISPLAY INVISIBLE (-6690 3750);
WIRE 16 -1 (-5400 3800)(-6450 3800);
FORCEPROP 2 LAST SIG_NAME TP_CPU0_RSVD_293
J 0
(-6425 3810);
DISPLAY 0.617021 (-6425 3810);
PAINT ORANGE (-6425 3810);
FORCEPROP 2 LASTPROP $XRERR UNIQUE?
J 0
(-6690 3800);
DISPLAY 0.638298 (-6690 3800);
PAINT MONO (-6690 3800);
DISPLAY INVISIBLE (-6690 3800);
WIRE 16 -1 (-5400 2650)(-6450 2650);
FORCEPROP 2 LAST SIG_NAME TP_CPU0_RSVD_274
J 0
(-6425 2660);
DISPLAY 0.617021 (-6425 2660);
PAINT ORANGE (-6425 2660);
FORCEPROP 2 LASTPROP $XRERR UNIQUE?
J 0
(-6690 2650);
DISPLAY 0.638298 (-6690 2650);
PAINT MONO (-6690 2650);
DISPLAY INVISIBLE (-6690 2650);
WIRE 16 -1 (-5400 2550)(-6450 2550);
FORCEPROP 2 LAST SIG_NAME TP_CPU0_RSVD_272
J 0
(-6425 2560);
DISPLAY 0.617021 (-6425 2560);
PAINT ORANGE (-6425 2560);
FORCEPROP 2 LASTPROP $XRERR UNIQUE?
J 0
(-6690 2550);
DISPLAY 0.638298 (-6690 2550);
PAINT MONO (-6690 2550);
DISPLAY INVISIBLE (-6690 2550);
WIRE 16 -1 (-5400 2800)(-6450 2800);
FORCEPROP 2 LAST SIG_NAME TP_CPU0_RSVD_276
J 0
(-6425 2810);
DISPLAY 0.617021 (-6425 2810);
PAINT ORANGE (-6425 2810);
FORCEPROP 2 LASTPROP $XRERR UNIQUE?
J 0
(-6690 2800);
DISPLAY 0.638298 (-6690 2800);
PAINT MONO (-6690 2800);
DISPLAY INVISIBLE (-6690 2800);
WIRE 16 -1 (-5400 2950)(-6450 2950);
FORCEPROP 2 LAST SIG_NAME TP_CPU0_RSVD_278
J 0
(-6425 2960);
DISPLAY 0.617021 (-6425 2960);
PAINT ORANGE (-6425 2960);
FORCEPROP 2 LASTPROP $XRERR UNIQUE?
J 0
(-6690 2950);
DISPLAY 0.638298 (-6690 2950);
PAINT MONO (-6690 2950);
DISPLAY INVISIBLE (-6690 2950);
WIRE 16 -1 (-5400 3050)(-6450 3050);
FORCEPROP 2 LAST SIG_NAME TP_CPU0_RSVD_280
J 0
(-6425 3060);
DISPLAY 0.617021 (-6425 3060);
PAINT ORANGE (-6425 3060);
FORCEPROP 2 LASTPROP $XRERR UNIQUE?
J 0
(-6690 3050);
DISPLAY 0.638298 (-6690 3050);
PAINT MONO (-6690 3050);
DISPLAY INVISIBLE (-6690 3050);
WIRE 16 -1 (-5400 2150)(-6450 2150);
FORCEPROP 2 LAST SIG_NAME TP_CPU0_RSVD_264
J 0
(-6425 2160);
DISPLAY 0.617021 (-6425 2160);
PAINT ORANGE (-6425 2160);
FORCEPROP 2 LASTPROP $XRERR UNIQUE?
J 0
(-6690 2150);
DISPLAY 0.638298 (-6690 2150);
PAINT MONO (-6690 2150);
DISPLAY INVISIBLE (-6690 2150);
WIRE 16 -1 (-5400 2050)(-6450 2050);
FORCEPROP 2 LAST SIG_NAME TP_CPU0_RSVD_262
J 0
(-6425 2060);
DISPLAY 0.617021 (-6425 2060);
PAINT ORANGE (-6425 2060);
FORCEPROP 2 LASTPROP $XRERR UNIQUE?
J 0
(-6690 2050);
DISPLAY 0.638298 (-6690 2050);
PAINT MONO (-6690 2050);
DISPLAY INVISIBLE (-6690 2050);
WIRE 16 -1 (-5400 2850)(-6450 2850);
FORCEPROP 2 LAST SIG_NAME TP_CPU0_RSVD_277
J 0
(-6425 2860);
DISPLAY 0.617021 (-6425 2860);
PAINT ORANGE (-6425 2860);
FORCEPROP 2 LASTPROP $XRERR UNIQUE?
J 0
(-6690 2850);
DISPLAY 0.638298 (-6690 2850);
PAINT MONO (-6690 2850);
DISPLAY INVISIBLE (-6690 2850);
WIRE 16 -1 (-5400 3000)(-6450 3000);
FORCEPROP 2 LAST SIG_NAME TP_CPU0_RSVD_279
J 0
(-6425 3010);
DISPLAY 0.617021 (-6425 3010);
PAINT ORANGE (-6425 3010);
FORCEPROP 2 LASTPROP $XRERR UNIQUE?
J 0
(-6690 3000);
DISPLAY 0.638298 (-6690 3000);
PAINT MONO (-6690 3000);
DISPLAY INVISIBLE (-6690 3000);
WIRE 16 -1 (-5400 3100)(-6450 3100);
FORCEPROP 2 LAST SIG_NAME TP_CPU0_RSVD_281
J 0
(-6425 3110);
DISPLAY 0.617021 (-6425 3110);
PAINT ORANGE (-6425 3110);
FORCEPROP 2 LASTPROP $XRERR UNIQUE?
J 0
(-6690 3100);
DISPLAY 0.638298 (-6690 3100);
PAINT MONO (-6690 3100);
DISPLAY INVISIBLE (-6690 3100);
WIRE 16 -1 (-5400 750)(-6450 750);
FORCEPROP 2 LAST SIG_NAME TP_CPU0_RSVD_242
J 0
(-6425 760);
DISPLAY 0.617021 (-6425 760);
PAINT ORANGE (-6425 760);
FORCEPROP 2 LASTPROP $XRERR UNIQUE?
J 0
(-6690 750);
DISPLAY 0.638298 (-6690 750);
PAINT MONO (-6690 750);
DISPLAY INVISIBLE (-6690 750);
WIRE 16 -1 (-5400 900)(-6450 900);
FORCEPROP 2 LAST SIG_NAME TP_CPU0_RSVD_243
J 0
(-6425 910);
DISPLAY 0.617021 (-6425 910);
PAINT ORANGE (-6425 910);
FORCEPROP 2 LASTPROP $XRERR UNIQUE?
J 0
(-6690 900);
DISPLAY 0.638298 (-6690 900);
PAINT MONO (-6690 900);
DISPLAY INVISIBLE (-6690 900);
WIRE 16 -1 (-5400 950)(-6450 950);
FORCEPROP 2 LAST SIG_NAME TP_CPU0_RSVD_244
J 0
(-6425 960);
DISPLAY 0.617021 (-6425 960);
PAINT ORANGE (-6425 960);
FORCEPROP 2 LASTPROP $XRERR UNIQUE?
J 0
(-6690 950);
DISPLAY 0.638298 (-6690 950);
PAINT MONO (-6690 950);
DISPLAY INVISIBLE (-6690 950);
WIRE 16 -1 (-5400 1000)(-6450 1000);
FORCEPROP 2 LAST SIG_NAME TP_CPU0_RSVD_245
J 0
(-6425 1010);
DISPLAY 0.617021 (-6425 1010);
PAINT ORANGE (-6425 1010);
FORCEPROP 2 LASTPROP $XRERR UNIQUE?
J 0
(-6690 1000);
DISPLAY 0.638298 (-6690 1000);
PAINT MONO (-6690 1000);
DISPLAY INVISIBLE (-6690 1000);
WIRE 16 -1 (-5400 1050)(-6450 1050);
FORCEPROP 2 LAST SIG_NAME TP_CPU0_RSVD_246
J 0
(-6425 1060);
DISPLAY 0.617021 (-6425 1060);
PAINT ORANGE (-6425 1060);
FORCEPROP 2 LASTPROP $XRERR UNIQUE?
J 0
(-6690 1050);
DISPLAY 0.638298 (-6690 1050);
PAINT MONO (-6690 1050);
DISPLAY INVISIBLE (-6690 1050);
WIRE 16 -1 (-5400 1100)(-6450 1100);
FORCEPROP 2 LAST SIG_NAME TP_CPU0_RSVD_247
J 0
(-6425 1110);
DISPLAY 0.617021 (-6425 1110);
PAINT ORANGE (-6425 1110);
FORCEPROP 2 LASTPROP $XRERR UNIQUE?
J 0
(-6690 1100);
DISPLAY 0.638298 (-6690 1100);
PAINT MONO (-6690 1100);
DISPLAY INVISIBLE (-6690 1100);
WIRE 16 -1 (-6450 1250)(-5400 1250);
FORCEPROP 2 LAST SIG_NAME TP_CPU0_RSVD_249
J 0
(-6425 1260);
DISPLAY 0.617021 (-6425 1260);
PAINT ORANGE (-6425 1260);
FORCEPROP 2 LASTPROP $XRERR UNIQUE?
J 0
(-6690 1250);
DISPLAY 0.638298 (-6690 1250);
PAINT MONO (-6690 1250);
DISPLAY INVISIBLE (-6690 1250);
WIRE 16 -1 (-6450 1300)(-5400 1300);
FORCEPROP 2 LAST SIG_NAME TP_CPU0_RSVD_250
J 0
(-6425 1310);
DISPLAY 0.617021 (-6425 1310);
PAINT ORANGE (-6425 1310);
FORCEPROP 2 LASTPROP $XRERR UNIQUE?
J 0
(-6690 1300);
DISPLAY 0.638298 (-6690 1300);
PAINT MONO (-6690 1300);
DISPLAY INVISIBLE (-6690 1300);
WIRE 16 -1 (-5400 1350)(-6450 1350);
FORCEPROP 2 LAST SIG_NAME TP_CPU0_RSVD_251
J 0
(-6425 1360);
DISPLAY 0.617021 (-6425 1360);
PAINT ORANGE (-6425 1360);
FORCEPROP 2 LASTPROP $XRERR UNIQUE?
J 0
(-6690 1350);
DISPLAY 0.638298 (-6690 1350);
PAINT MONO (-6690 1350);
DISPLAY INVISIBLE (-6690 1350);
WIRE 16 -1 (-6450 1800)(-5400 1800);
FORCEPROP 2 LAST SIG_NAME TP_CPU0_RSVD_258
J 0
(-6425 1810);
DISPLAY 0.617021 (-6425 1810);
PAINT ORANGE (-6425 1810);
FORCEPROP 2 LASTPROP $XRERR UNIQUE?
J 0
(-6690 1800);
DISPLAY 0.638298 (-6690 1800);
PAINT MONO (-6690 1800);
DISPLAY INVISIBLE (-6690 1800);
WIRE 16 -1 (-5400 2200)(-6450 2200);
FORCEPROP 2 LAST SIG_NAME TP_CPU0_RSVD_265
J 0
(-6425 2210);
DISPLAY 0.617021 (-6425 2210);
PAINT ORANGE (-6425 2210);
FORCEPROP 2 LASTPROP $XRERR UNIQUE?
J 0
(-6690 2200);
DISPLAY 0.638298 (-6690 2200);
PAINT MONO (-6690 2200);
DISPLAY INVISIBLE (-6690 2200);
WIRE 16 -1 (-5400 1400)(-6450 1400);
FORCEPROP 2 LAST SIG_NAME TP_CPU0_RSVD_252
J 0
(-6425 1410);
DISPLAY 0.617021 (-6425 1410);
PAINT ORANGE (-6425 1410);
FORCEPROP 2 LASTPROP $XRERR UNIQUE?
J 0
(-6690 1400);
DISPLAY 0.638298 (-6690 1400);
PAINT MONO (-6690 1400);
DISPLAY INVISIBLE (-6690 1400);
WIRE 16 -1 (-5400 4100)(-6450 4100);
FORCEPROP 2 LAST SIG_NAME TP_CPU0_RSVD_299
J 0
(-6425 4110);
DISPLAY 0.617021 (-6425 4110);
PAINT ORANGE (-6425 4110);
FORCEPROP 2 LASTPROP $XRERR UNIQUE?
J 0
(-6690 4100);
DISPLAY 0.638298 (-6690 4100);
PAINT MONO (-6690 4100);
DISPLAY INVISIBLE (-6690 4100);
WIRE 16 -1 (-5400 4150)(-6450 4150);
FORCEPROP 2 LAST SIG_NAME TP_CPU0_RSVD_300
J 0
(-6425 4160);
DISPLAY 0.617021 (-6425 4160);
PAINT ORANGE (-6425 4160);
FORCEPROP 2 LASTPROP $XRERR UNIQUE?
J 0
(-6690 4150);
DISPLAY 0.638298 (-6690 4150);
PAINT MONO (-6690 4150);
DISPLAY INVISIBLE (-6690 4150);
DOT 1 (-2750 1200);
DOT 1 (-2750 900);
DOT 1 (-2750 1150);
DOT 1 (-2750 1100);
DOT 1 (-7300 4250);
DOT 1 (-300 2550);
DOT 1 (-5575 3950);
DOT 1 (-5575 3900);
DOT 1 (-5575 4250);
DOT 1 (-1100 1650);
DOT 1 (-1100 1500);
DOT 1 (-1100 1100);
FORCENOTE
TP FAB3 RECONNECT 0921
(-2700 2425) 0;
DISPLAY LEFT (-2700 2425);
DISPLAY 0.638298 (-2700 2425);
PAINT RED (-2700 2425);
FORCENOTE
SKYLAKE - SKT0 - 2 OF 21
(-1625 150) 0;
DISPLAY LEFT (-1625 150);
DISPLAY 1.021277 (-1625 150);
PAINT RED (-1625 150);
FORCENOTE
BOM_COST=PROC_SOCKET
(-7925 225) 0;
DISPLAY LEFT (-7925 225);
DISPLAY 1.723404 (-7925 225);
PAINT PURPLE (-7925 225);
FORCENOTE
ROOM=CPU0
(-7925 350) 0;
DISPLAY LEFT (-7925 350);
DISPLAY 1.723404 (-7925 350);
PAINT PURPLE (-7925 350);
QUIT
